FILE_TYPE = MACRO_DRAWING;
SET COLOR_WIRE YELLOW;
SET COLOR_PROP ORANGE;
SET COLOR_DOT WHITE;
SET COLOR_ARC YELLOW;
SET COLOR_BODY GREEN;
SET COLOR_NOTE PURPLE;
SET PROP_DISPLAY VALUE;
SET PAGE_NUMBER P11;
FORCEADD GENOA_SP5..2
(-4550 3475);
FORCEPROP 1 LAST LOCATION U25
J 0
(-5195 6331);
DISPLAY 0.489362 (-5195 6331);
PAINT SKYBLUE (-5195 6331);
FORCEPROP 0 LAST $SEC 2
J 0
(-5175 6375);
DISPLAY 0.680851 (-5175 6375);
PAINT MONO (-5175 6375);
DISPLAY INVISIBLE (-5175 6375);
FORCEPROP 0 LAST CDS_SEC 2
J 0
(-5200 6300);
DISPLAY 1.021277 (-5200 6300);
DISPLAY INVISIBLE (-5200 6300);
FORCEPROP 0 LASTPIN (-5350 2875) $PN BC64
J 2
(-5360 2885);
DISPLAY 0.489362 (-5360 2885);
PAINT MONO (-5360 2885);
FORCEPROP 0 LASTPIN (-5350 2825) $PN BD63
J 2
(-5360 2835);
DISPLAY 0.489362 (-5360 2835);
PAINT MONO (-5360 2835);
FORCEPROP 0 LASTPIN (-5350 1725) $PN BF63
J 2
(-5360 1735);
DISPLAY 0.489362 (-5360 1735);
PAINT MONO (-5360 1735);
FORCEPROP 0 LASTPIN (-5350 1675) $PN BG64
J 2
(-5360 1685);
DISPLAY 0.489362 (-5360 1685);
PAINT MONO (-5360 1685);
FORCEPROP 0 LASTPIN (-5350 2025) $PN AT62
J 2
(-5360 2035);
DISPLAY 0.489362 (-5360 2035);
PAINT MONO (-5360 2035);
FORCEPROP 0 LASTPIN (-5350 1925) $PN AU62
J 2
(-5360 1935);
DISPLAY 0.489362 (-5360 1935);
PAINT MONO (-5360 1935);
FORCEPROP 0 LASTPIN (-5350 2725) $PN AV63
J 2
(-5360 2735);
DISPLAY 0.489362 (-5360 2735);
PAINT MONO (-5360 2735);
FORCEPROP 0 LASTPIN (-5350 2675) $PN AW62
J 2
(-5360 2685);
DISPLAY 0.489362 (-5360 2685);
PAINT MONO (-5360 2685);
FORCEPROP 0 LASTPIN (-5350 2575) $PN BN62
J 2
(-5360 2585);
DISPLAY 0.489362 (-5360 2585);
PAINT MONO (-5360 2585);
FORCEPROP 0 LASTPIN (-5350 1575) $PN AU64
J 2
(-5360 1585);
DISPLAY 0.489362 (-5360 1585);
PAINT MONO (-5360 1585);
FORCEPROP 0 LASTPIN (-5350 1525) $PN AV62
J 2
(-5360 1535);
DISPLAY 0.489362 (-5360 1535);
PAINT MONO (-5360 1535);
FORCEPROP 0 LASTPIN (-5350 1425) $PN BP62
J 2
(-5360 1435);
DISPLAY 0.489362 (-5360 1435);
PAINT MONO (-5360 1435);
FORCEPROP 0 LASTPIN (-5350 3725) $PN AW64
J 2
(-5360 3735);
DISPLAY 0.489362 (-5360 3735);
PAINT MONO (-5360 3735);
FORCEPROP 0 LASTPIN (-5350 3675) $PN AY63
J 2
(-5360 3685);
DISPLAY 0.489362 (-5360 3685);
PAINT MONO (-5360 3685);
FORCEPROP 0 LASTPIN (-5350 3625) $PN AY62
J 2
(-5360 3635);
DISPLAY 0.489362 (-5360 3635);
PAINT MONO (-5360 3635);
FORCEPROP 0 LASTPIN (-5350 3575) $PN BA62
J 2
(-5360 3585);
DISPLAY 0.489362 (-5360 3585);
PAINT MONO (-5360 3585);
FORCEPROP 0 LASTPIN (-5350 3525) $PN BA64
J 2
(-5360 3535);
DISPLAY 0.489362 (-5360 3535);
PAINT MONO (-5360 3535);
FORCEPROP 0 LASTPIN (-5350 3475) $PN BB63
J 2
(-5360 3485);
DISPLAY 0.489362 (-5360 3485);
PAINT MONO (-5360 3485);
FORCEPROP 0 LASTPIN (-5350 3425) $PN BB62
J 2
(-5360 3435);
DISPLAY 0.489362 (-5360 3435);
PAINT MONO (-5360 3435);
FORCEPROP 0 LASTPIN (-3750 2275) $PN AJ64
J 0
(-3740 2285);
DISPLAY 0.489362 (-3740 2285);
PAINT MONO (-3740 2285);
FORCEPROP 0 LASTPIN (-3750 2225) $PN AK62
J 0
(-3740 2235);
DISPLAY 0.489362 (-3740 2235);
PAINT MONO (-3740 2235);
FORCEPROP 0 LASTPIN (-3750 2175) $PN AK63
J 0
(-3740 2185);
DISPLAY 0.489362 (-3740 2185);
PAINT MONO (-3740 2185);
FORCEPROP 0 LASTPIN (-3750 2125) $PN AL62
J 0
(-3740 2135);
DISPLAY 0.489362 (-3740 2135);
PAINT MONO (-3740 2135);
FORCEPROP 0 LASTPIN (-3750 2075) $PN AN64
J 0
(-3740 2085);
DISPLAY 0.489362 (-3740 2085);
PAINT MONO (-3740 2085);
FORCEPROP 0 LASTPIN (-3750 2025) $PN AP62
J 0
(-3740 2035);
DISPLAY 0.489362 (-3740 2035);
PAINT MONO (-3740 2035);
FORCEPROP 0 LASTPIN (-3750 1975) $PN AP63
J 0
(-3740 1985);
DISPLAY 0.489362 (-3740 1985);
PAINT MONO (-3740 1985);
FORCEPROP 0 LASTPIN (-3750 1925) $PN AR62
J 0
(-3740 1935);
DISPLAY 0.489362 (-3740 1935);
PAINT MONO (-3740 1935);
FORCEPROP 0 LASTPIN (-3750 5875) $PN E64
J 0
(-3740 5885);
DISPLAY 0.489362 (-3740 5885);
PAINT MONO (-3740 5885);
FORCEPROP 0 LASTPIN (-3750 5825) $PN F62
J 0
(-3740 5835);
DISPLAY 0.489362 (-3740 5835);
PAINT MONO (-3740 5835);
FORCEPROP 0 LASTPIN (-3750 5775) $PN F63
J 0
(-3740 5785);
DISPLAY 0.489362 (-3740 5785);
PAINT MONO (-3740 5785);
FORCEPROP 0 LASTPIN (-3750 5725) $PN G62
J 0
(-3740 5735);
DISPLAY 0.489362 (-3740 5735);
PAINT MONO (-3740 5735);
FORCEPROP 0 LASTPIN (-3750 5675) $PN J64
J 0
(-3740 5685);
DISPLAY 0.489362 (-3740 5685);
PAINT MONO (-3740 5685);
FORCEPROP 0 LASTPIN (-3750 5625) $PN K62
J 0
(-3740 5635);
DISPLAY 0.489362 (-3740 5635);
PAINT MONO (-3740 5635);
FORCEPROP 0 LASTPIN (-3750 5575) $PN K63
J 0
(-3740 5585);
DISPLAY 0.489362 (-3740 5585);
PAINT MONO (-3740 5585);
FORCEPROP 0 LASTPIN (-3750 5525) $PN L62
J 0
(-3740 5535);
DISPLAY 0.489362 (-3740 5535);
PAINT MONO (-3740 5535);
FORCEPROP 0 LASTPIN (-3750 5425) $PN L64
J 0
(-3740 5435);
DISPLAY 0.489362 (-3740 5435);
PAINT MONO (-3740 5435);
FORCEPROP 0 LASTPIN (-3750 5375) $PN M62
J 0
(-3740 5385);
DISPLAY 0.489362 (-3740 5385);
PAINT MONO (-3740 5385);
FORCEPROP 0 LASTPIN (-3750 5325) $PN M63
J 0
(-3740 5335);
DISPLAY 0.489362 (-3740 5335);
PAINT MONO (-3740 5335);
FORCEPROP 0 LASTPIN (-3750 5275) $PN N62
J 0
(-3740 5285);
DISPLAY 0.489362 (-3740 5285);
PAINT MONO (-3740 5285);
FORCEPROP 0 LASTPIN (-3750 5225) $PN R64
J 0
(-3740 5235);
DISPLAY 0.489362 (-3740 5235);
PAINT MONO (-3740 5235);
FORCEPROP 0 LASTPIN (-3750 5175) $PN T62
J 0
(-3740 5185);
DISPLAY 0.489362 (-3740 5185);
PAINT MONO (-3740 5185);
FORCEPROP 0 LASTPIN (-3750 5125) $PN T63
J 0
(-3740 5135);
DISPLAY 0.489362 (-3740 5135);
PAINT MONO (-3740 5135);
FORCEPROP 0 LASTPIN (-3750 5075) $PN U62
J 0
(-3740 5085);
DISPLAY 0.489362 (-3740 5085);
PAINT MONO (-3740 5085);
FORCEPROP 0 LASTPIN (-3750 4975) $PN U64
J 0
(-3740 4985);
DISPLAY 0.489362 (-3740 4985);
PAINT MONO (-3740 4985);
FORCEPROP 0 LASTPIN (-3750 4925) $PN V62
J 0
(-3740 4935);
DISPLAY 0.489362 (-3740 4935);
PAINT MONO (-3740 4935);
FORCEPROP 0 LASTPIN (-3750 4875) $PN V63
J 0
(-3740 4885);
DISPLAY 0.489362 (-3740 4885);
PAINT MONO (-3740 4885);
FORCEPROP 0 LASTPIN (-3750 4825) $PN W62
J 0
(-3740 4835);
DISPLAY 0.489362 (-3740 4835);
PAINT MONO (-3740 4835);
FORCEPROP 0 LASTPIN (-3750 4775) $PN AA64
J 0
(-3740 4785);
DISPLAY 0.489362 (-3740 4785);
PAINT MONO (-3740 4785);
FORCEPROP 0 LASTPIN (-3750 4725) $PN AB62
J 0
(-3740 4735);
DISPLAY 0.489362 (-3740 4735);
PAINT MONO (-3740 4735);
FORCEPROP 0 LASTPIN (-3750 4675) $PN AB63
J 0
(-3740 4685);
DISPLAY 0.489362 (-3740 4685);
PAINT MONO (-3740 4685);
FORCEPROP 0 LASTPIN (-3750 4625) $PN AC62
J 0
(-3740 4635);
DISPLAY 0.489362 (-3740 4635);
PAINT MONO (-3740 4635);
FORCEPROP 0 LASTPIN (-3750 4525) $PN AC64
J 0
(-3740 4535);
DISPLAY 0.489362 (-3740 4535);
PAINT MONO (-3740 4535);
FORCEPROP 0 LASTPIN (-3750 4475) $PN AD62
J 0
(-3740 4485);
DISPLAY 0.489362 (-3740 4485);
PAINT MONO (-3740 4485);
FORCEPROP 0 LASTPIN (-3750 4425) $PN AD63
J 0
(-3740 4435);
DISPLAY 0.489362 (-3740 4435);
PAINT MONO (-3740 4435);
FORCEPROP 0 LASTPIN (-3750 4375) $PN AE62
J 0
(-3740 4385);
DISPLAY 0.489362 (-3740 4385);
PAINT MONO (-3740 4385);
FORCEPROP 0 LASTPIN (-3750 4325) $PN AG64
J 0
(-3740 4335);
DISPLAY 0.489362 (-3740 4335);
PAINT MONO (-3740 4335);
FORCEPROP 0 LASTPIN (-3750 4275) $PN AH62
J 0
(-3740 4285);
DISPLAY 0.489362 (-3740 4285);
PAINT MONO (-3740 4285);
FORCEPROP 0 LASTPIN (-3750 4225) $PN AH63
J 0
(-3740 4235);
DISPLAY 0.489362 (-3740 4235);
PAINT MONO (-3740 4235);
FORCEPROP 0 LASTPIN (-3750 4175) $PN AJ62
J 0
(-3740 4185);
DISPLAY 0.489362 (-3740 4185);
PAINT MONO (-3740 4185);
FORCEPROP 0 LASTPIN (-5350 5875) $PN G64
J 2
(-5360 5885);
DISPLAY 0.489362 (-5360 5885);
PAINT MONO (-5360 5885);
FORCEPROP 0 LASTPIN (-5350 5775) $PN N64
J 2
(-5360 5785);
DISPLAY 0.489362 (-5360 5785);
PAINT MONO (-5360 5785);
FORCEPROP 0 LASTPIN (-5350 5675) $PN W64
J 2
(-5360 5685);
DISPLAY 0.489362 (-5360 5685);
PAINT MONO (-5360 5685);
FORCEPROP 0 LASTPIN (-5350 5575) $PN AE64
J 2
(-5360 5585);
DISPLAY 0.489362 (-5360 5585);
PAINT MONO (-5360 5585);
FORCEPROP 0 LASTPIN (-5350 5475) $PN AL64
J 2
(-5360 5485);
DISPLAY 0.489362 (-5360 5485);
PAINT MONO (-5360 5485);
FORCEPROP 0 LASTPIN (-5350 5375) $PN J62
J 2
(-5360 5385);
DISPLAY 0.489362 (-5360 5385);
PAINT MONO (-5360 5385);
FORCEPROP 0 LASTPIN (-5350 5275) $PN R62
J 2
(-5360 5285);
DISPLAY 0.489362 (-5360 5285);
PAINT MONO (-5360 5285);
FORCEPROP 0 LASTPIN (-5350 5175) $PN AA62
J 2
(-5360 5185);
DISPLAY 0.489362 (-5360 5185);
PAINT MONO (-5360 5185);
FORCEPROP 0 LASTPIN (-5350 5075) $PN AG62
J 2
(-5360 5085);
DISPLAY 0.489362 (-5360 5085);
PAINT MONO (-5360 5085);
FORCEPROP 0 LASTPIN (-5350 4975) $PN AN62
J 2
(-5360 4985);
DISPLAY 0.489362 (-5360 4985);
PAINT MONO (-5360 4985);
FORCEPROP 0 LASTPIN (-5350 5825) $PN H63
J 2
(-5360 5835);
DISPLAY 0.489362 (-5360 5835);
PAINT MONO (-5360 5835);
FORCEPROP 0 LASTPIN (-5350 5725) $PN P63
J 2
(-5360 5735);
DISPLAY 0.489362 (-5360 5735);
PAINT MONO (-5360 5735);
FORCEPROP 0 LASTPIN (-5350 5625) $PN Y63
J 2
(-5360 5635);
DISPLAY 0.489362 (-5360 5635);
PAINT MONO (-5360 5635);
FORCEPROP 0 LASTPIN (-5350 5525) $PN AF63
J 2
(-5360 5535);
DISPLAY 0.489362 (-5360 5535);
PAINT MONO (-5360 5535);
FORCEPROP 0 LASTPIN (-5350 5425) $PN AM63
J 2
(-5360 5435);
DISPLAY 0.489362 (-5360 5435);
PAINT MONO (-5360 5435);
FORCEPROP 0 LASTPIN (-5350 5325) $PN H62
J 2
(-5360 5335);
DISPLAY 0.489362 (-5360 5335);
PAINT MONO (-5360 5335);
FORCEPROP 0 LASTPIN (-5350 5225) $PN P62
J 2
(-5360 5235);
DISPLAY 0.489362 (-5360 5235);
PAINT MONO (-5360 5235);
FORCEPROP 0 LASTPIN (-5350 5125) $PN Y62
J 2
(-5360 5135);
DISPLAY 0.489362 (-5360 5135);
PAINT MONO (-5360 5135);
FORCEPROP 0 LASTPIN (-5350 5025) $PN AF62
J 2
(-5360 5035);
DISPLAY 0.489362 (-5360 5035);
PAINT MONO (-5360 5035);
FORCEPROP 0 LASTPIN (-5350 4925) $PN AM62
J 2
(-5360 4935);
DISPLAY 0.489362 (-5360 4935);
PAINT MONO (-5360 4935);
FORCEPROP 0 LASTPIN (-5350 2475) $PN BC62
J 2
(-5360 2485);
DISPLAY 0.489362 (-5360 2485);
PAINT MONO (-5360 2485);
FORCEPROP 0 LASTPIN (-5350 2375) $PN BM62
J 2
(-5360 2385);
DISPLAY 0.489362 (-5360 2385);
PAINT MONO (-5360 2385);
FORCEPROP 0 LASTPIN (-5350 2325) $PN BN64
J 2
(-5360 2335);
DISPLAY 0.489362 (-5360 2335);
PAINT MONO (-5360 2335);
FORCEPROP 0 LASTPIN (-5350 2225) $PN BP63
J 2
(-5360 2235);
DISPLAY 0.489362 (-5360 2235);
PAINT MONO (-5360 2235);
FORCEPROP 0 LASTPIN (-5350 1325) $PN BL62
J 2
(-5360 1335);
DISPLAY 0.489362 (-5360 1335);
PAINT MONO (-5360 1335);
FORCEPROP 0 LASTPIN (-5350 1275) $PN BM63
J 2
(-5360 1285);
DISPLAY 0.489362 (-5360 1285);
PAINT MONO (-5360 1285);
FORCEPROP 0 LASTPIN (-5350 1175) $PN BR64
J 2
(-5360 1185);
DISPLAY 0.489362 (-5360 1185);
PAINT MONO (-5360 1185);
FORCEPROP 0 LASTPIN (-5350 3325) $PN BG62
J 2
(-5360 3335);
DISPLAY 0.489362 (-5360 3335);
PAINT MONO (-5360 3335);
FORCEPROP 0 LASTPIN (-5350 3275) $PN BH62
J 2
(-5360 3285);
DISPLAY 0.489362 (-5360 3285);
PAINT MONO (-5360 3285);
FORCEPROP 0 LASTPIN (-5350 3225) $PN BH63
J 2
(-5360 3235);
DISPLAY 0.489362 (-5360 3235);
PAINT MONO (-5360 3235);
FORCEPROP 0 LASTPIN (-5350 3175) $PN BJ64
J 2
(-5360 3185);
DISPLAY 0.489362 (-5360 3185);
PAINT MONO (-5360 3185);
FORCEPROP 0 LASTPIN (-5350 3125) $PN BJ62
J 2
(-5360 3135);
DISPLAY 0.489362 (-5360 3135);
PAINT MONO (-5360 3135);
FORCEPROP 0 LASTPIN (-5350 3075) $PN BK62
J 2
(-5360 3085);
DISPLAY 0.489362 (-5360 3085);
PAINT MONO (-5360 3085);
FORCEPROP 0 LASTPIN (-5350 3025) $PN BK63
J 2
(-5360 3035);
DISPLAY 0.489362 (-5360 3035);
PAINT MONO (-5360 3035);
FORCEPROP 0 LASTPIN (-3750 1825) $PN BY63
J 0
(-3740 1835);
DISPLAY 0.489362 (-3740 1835);
PAINT MONO (-3740 1835);
FORCEPROP 0 LASTPIN (-3750 1775) $PN CA62
J 0
(-3740 1785);
DISPLAY 0.489362 (-3740 1785);
PAINT MONO (-3740 1785);
FORCEPROP 0 LASTPIN (-3750 1725) $PN CA64
J 0
(-3740 1735);
DISPLAY 0.489362 (-3740 1735);
PAINT MONO (-3740 1735);
FORCEPROP 0 LASTPIN (-3750 1675) $PN CB62
J 0
(-3740 1685);
DISPLAY 0.489362 (-3740 1685);
PAINT MONO (-3740 1685);
FORCEPROP 0 LASTPIN (-3750 1625) $PN BT63
J 0
(-3740 1635);
DISPLAY 0.489362 (-3740 1635);
PAINT MONO (-3740 1635);
FORCEPROP 0 LASTPIN (-3750 1575) $PN BU62
J 0
(-3740 1585);
DISPLAY 0.489362 (-3740 1585);
PAINT MONO (-3740 1585);
FORCEPROP 0 LASTPIN (-3750 1525) $PN BU64
J 0
(-3740 1535);
DISPLAY 0.489362 (-3740 1535);
PAINT MONO (-3740 1535);
FORCEPROP 0 LASTPIN (-3750 1475) $PN BV62
J 0
(-3740 1485);
DISPLAY 0.489362 (-3740 1485);
PAINT MONO (-3740 1485);
FORCEPROP 0 LASTPIN (-3750 4075) $PN CB63
J 0
(-3740 4085);
DISPLAY 0.489362 (-3740 4085);
PAINT MONO (-3740 4085);
FORCEPROP 0 LASTPIN (-3750 4025) $PN CC62
J 0
(-3740 4035);
DISPLAY 0.489362 (-3740 4035);
PAINT MONO (-3740 4035);
FORCEPROP 0 LASTPIN (-3750 3975) $PN CC64
J 0
(-3740 3985);
DISPLAY 0.489362 (-3740 3985);
PAINT MONO (-3740 3985);
FORCEPROP 0 LASTPIN (-3750 3925) $PN CD62
J 0
(-3740 3935);
DISPLAY 0.489362 (-3740 3935);
PAINT MONO (-3740 3935);
FORCEPROP 0 LASTPIN (-3750 3875) $PN CF63
J 0
(-3740 3885);
DISPLAY 0.489362 (-3740 3885);
PAINT MONO (-3740 3885);
FORCEPROP 0 LASTPIN (-3750 3825) $PN CG62
J 0
(-3740 3835);
DISPLAY 0.489362 (-3740 3835);
PAINT MONO (-3740 3835);
FORCEPROP 0 LASTPIN (-3750 3775) $PN CG64
J 0
(-3740 3785);
DISPLAY 0.489362 (-3740 3785);
PAINT MONO (-3740 3785);
FORCEPROP 0 LASTPIN (-3750 3725) $PN CH62
J 0
(-3740 3735);
DISPLAY 0.489362 (-3740 3735);
PAINT MONO (-3740 3735);
FORCEPROP 0 LASTPIN (-3750 3625) $PN CH63
J 0
(-3740 3635);
DISPLAY 0.489362 (-3740 3635);
PAINT MONO (-3740 3635);
FORCEPROP 0 LASTPIN (-3750 3575) $PN CJ62
J 0
(-3740 3585);
DISPLAY 0.489362 (-3740 3585);
PAINT MONO (-3740 3585);
FORCEPROP 0 LASTPIN (-3750 3525) $PN CJ64
J 0
(-3740 3535);
DISPLAY 0.489362 (-3740 3535);
PAINT MONO (-3740 3535);
FORCEPROP 0 LASTPIN (-3750 3475) $PN CK62
J 0
(-3740 3485);
DISPLAY 0.489362 (-3740 3485);
PAINT MONO (-3740 3485);
FORCEPROP 0 LASTPIN (-3750 3425) $PN CM63
J 0
(-3740 3435);
DISPLAY 0.489362 (-3740 3435);
PAINT MONO (-3740 3435);
FORCEPROP 0 LASTPIN (-3750 3375) $PN CN62
J 0
(-3740 3385);
DISPLAY 0.489362 (-3740 3385);
PAINT MONO (-3740 3385);
FORCEPROP 0 LASTPIN (-3750 3325) $PN CN64
J 0
(-3740 3335);
DISPLAY 0.489362 (-3740 3335);
PAINT MONO (-3740 3335);
FORCEPROP 0 LASTPIN (-3750 3275) $PN CP62
J 0
(-3740 3285);
DISPLAY 0.489362 (-3740 3285);
PAINT MONO (-3740 3285);
FORCEPROP 0 LASTPIN (-3750 3175) $PN CP63
J 0
(-3740 3185);
DISPLAY 0.489362 (-3740 3185);
PAINT MONO (-3740 3185);
FORCEPROP 0 LASTPIN (-3750 3125) $PN CR62
J 0
(-3740 3135);
DISPLAY 0.489362 (-3740 3135);
PAINT MONO (-3740 3135);
FORCEPROP 0 LASTPIN (-3750 3075) $PN CR64
J 0
(-3740 3085);
DISPLAY 0.489362 (-3740 3085);
PAINT MONO (-3740 3085);
FORCEPROP 0 LASTPIN (-3750 3025) $PN CT62
J 0
(-3740 3035);
DISPLAY 0.489362 (-3740 3035);
PAINT MONO (-3740 3035);
FORCEPROP 0 LASTPIN (-3750 2975) $PN CV63
J 0
(-3740 2985);
DISPLAY 0.489362 (-3740 2985);
PAINT MONO (-3740 2985);
FORCEPROP 0 LASTPIN (-3750 2925) $PN CW62
J 0
(-3740 2935);
DISPLAY 0.489362 (-3740 2935);
PAINT MONO (-3740 2935);
FORCEPROP 0 LASTPIN (-3750 2875) $PN CW64
J 0
(-3740 2885);
DISPLAY 0.489362 (-3740 2885);
PAINT MONO (-3740 2885);
FORCEPROP 0 LASTPIN (-3750 2825) $PN CY62
J 0
(-3740 2835);
DISPLAY 0.489362 (-3740 2835);
PAINT MONO (-3740 2835);
FORCEPROP 0 LASTPIN (-3750 2725) $PN CY63
J 0
(-3740 2735);
DISPLAY 0.489362 (-3740 2735);
PAINT MONO (-3740 2735);
FORCEPROP 0 LASTPIN (-3750 2675) $PN DA62
J 0
(-3740 2685);
DISPLAY 0.489362 (-3740 2685);
PAINT MONO (-3740 2685);
FORCEPROP 0 LASTPIN (-3750 2625) $PN DA64
J 0
(-3740 2635);
DISPLAY 0.489362 (-3740 2635);
PAINT MONO (-3740 2635);
FORCEPROP 0 LASTPIN (-3750 2575) $PN DB62
J 0
(-3740 2585);
DISPLAY 0.489362 (-3740 2585);
PAINT MONO (-3740 2585);
FORCEPROP 0 LASTPIN (-3750 2525) $PN DD63
J 0
(-3740 2535);
DISPLAY 0.489362 (-3740 2535);
PAINT MONO (-3740 2535);
FORCEPROP 0 LASTPIN (-3750 2475) $PN DE62
J 0
(-3740 2485);
DISPLAY 0.489362 (-3740 2485);
PAINT MONO (-3740 2485);
FORCEPROP 0 LASTPIN (-3750 2425) $PN DE64
J 0
(-3740 2435);
DISPLAY 0.489362 (-3740 2435);
PAINT MONO (-3740 2435);
FORCEPROP 0 LASTPIN (-3750 2375) $PN DF62
J 0
(-3740 2385);
DISPLAY 0.489362 (-3740 2385);
PAINT MONO (-3740 2385);
FORCEPROP 0 LASTPIN (-5350 4825) $PN CD63
J 2
(-5360 4835);
DISPLAY 0.489362 (-5360 4835);
PAINT MONO (-5360 4835);
FORCEPROP 0 LASTPIN (-5350 4725) $PN CK63
J 2
(-5360 4735);
DISPLAY 0.489362 (-5360 4735);
PAINT MONO (-5360 4735);
FORCEPROP 0 LASTPIN (-5350 4625) $PN CT63
J 2
(-5360 4635);
DISPLAY 0.489362 (-5360 4635);
PAINT MONO (-5360 4635);
FORCEPROP 0 LASTPIN (-5350 4525) $PN DB63
J 2
(-5360 4535);
DISPLAY 0.489362 (-5360 4535);
PAINT MONO (-5360 4535);
FORCEPROP 0 LASTPIN (-5350 4425) $PN BY62
J 2
(-5360 4435);
DISPLAY 0.489362 (-5360 4435);
PAINT MONO (-5360 4435);
FORCEPROP 0 LASTPIN (-5350 4325) $PN CF62
J 2
(-5360 4335);
DISPLAY 0.489362 (-5360 4335);
PAINT MONO (-5360 4335);
FORCEPROP 0 LASTPIN (-5350 4225) $PN CM62
J 2
(-5360 4235);
DISPLAY 0.489362 (-5360 4235);
PAINT MONO (-5360 4235);
FORCEPROP 0 LASTPIN (-5350 4125) $PN CV62
J 2
(-5360 4135);
DISPLAY 0.489362 (-5360 4135);
PAINT MONO (-5360 4135);
FORCEPROP 0 LASTPIN (-5350 4025) $PN DD62
J 2
(-5360 4035);
DISPLAY 0.489362 (-5360 4035);
PAINT MONO (-5360 4035);
FORCEPROP 0 LASTPIN (-5350 3925) $PN BV63
J 2
(-5360 3935);
DISPLAY 0.489362 (-5360 3935);
PAINT MONO (-5360 3935);
FORCEPROP 0 LASTPIN (-5350 4775) $PN CE64
J 2
(-5360 4785);
DISPLAY 0.489362 (-5360 4785);
PAINT MONO (-5360 4785);
FORCEPROP 0 LASTPIN (-5350 4675) $PN CL64
J 2
(-5360 4685);
DISPLAY 0.489362 (-5360 4685);
PAINT MONO (-5360 4685);
FORCEPROP 0 LASTPIN (-5350 4575) $PN CU64
J 2
(-5360 4585);
DISPLAY 0.489362 (-5360 4585);
PAINT MONO (-5360 4585);
FORCEPROP 0 LASTPIN (-5350 4475) $PN DC64
J 2
(-5360 4485);
DISPLAY 0.489362 (-5360 4485);
PAINT MONO (-5360 4485);
FORCEPROP 0 LASTPIN (-5350 4375) $PN BW62
J 2
(-5360 4385);
DISPLAY 0.489362 (-5360 4385);
PAINT MONO (-5360 4385);
FORCEPROP 0 LASTPIN (-5350 4275) $PN CE62
J 2
(-5360 4285);
DISPLAY 0.489362 (-5360 4285);
PAINT MONO (-5360 4285);
FORCEPROP 0 LASTPIN (-5350 4175) $PN CL62
J 2
(-5360 4185);
DISPLAY 0.489362 (-5360 4185);
PAINT MONO (-5360 4185);
FORCEPROP 0 LASTPIN (-5350 4075) $PN CU62
J 2
(-5360 4085);
DISPLAY 0.489362 (-5360 4085);
PAINT MONO (-5360 4085);
FORCEPROP 0 LASTPIN (-5350 3975) $PN DC62
J 2
(-5360 3985);
DISPLAY 0.489362 (-5360 3985);
PAINT MONO (-5360 3985);
FORCEPROP 0 LASTPIN (-5350 3875) $PN BW64
J 2
(-5360 3885);
DISPLAY 0.489362 (-5360 3885);
PAINT MONO (-5360 3885);
FORCEPROP 0 LASTPIN (-5350 2125) $PN BL64
J 2
(-5360 2135);
DISPLAY 0.489362 (-5360 2135);
PAINT MONO (-5360 2135);
FORCEPROP 0 LASTPIN (-5350 1075) $PN BF62
J 2
(-5360 1085);
DISPLAY 0.489362 (-5360 1085);
PAINT MONO (-5360 1085);
FORCEPROP 2 LAST PART_TYPE SMLF
J 0
(-5200 6230);
DISPLAY 1.021277 (-5200 6230);
FORCEPROP 1 LAST MATERIAL IO
J 0
(-5195 6057);
DISPLAY 0.489362 (-5195 6057);
PAINT SKYBLUE (-5195 6057);
FORCEPROP 2 LAST VALUE SOCKET6096_13568-001
J 0
(-5200 6130);
DISPLAY 0.489362 (-5200 6130);
PAINT SKYBLUE (-5200 6130);
FORCEPROP 1 LAST CDS_LMAN_SYM_OUTLINE -650,2550,650,-2550
J 0
(-4550 3475);
DISPLAY 0.468085 (-4550 3475);
PAINT GREEN (-4550 3475);
DISPLAY INVISIBLE (-4550 3475);
FORCEPROP 2 LAST CDS_LIB pure_quanta
J 0
(-4550 3475);
DISPLAY INVISIBLE (-4550 3475);
FORCEPROP 1 LAST NEEDS_NO_SIZE TRUE
J 0
(-4550 3475);
DISPLAY 0.723404 (-4550 3475);
PAINT GREEN (-4550 3475);
DISPLAY INVISIBLE (-4550 3475);
FORCEPROP 1 LAST PATH I171
J 0
(-4550 3475);
DISPLAY 0.723404 (-4550 3475);
PAINT GREEN (-4550 3475);
DISPLAY INVISIBLE (-4550 3475);
FORCEPROP 1 LAST PART_NUMBER DGA^6000030
J 0
(-5195 6184);
DISPLAY 0.489362 (-5195 6184);
PAINT SKYBLUE (-5195 6184);
DISPLAY INVISIBLE (-5195 6184);
FORCEADD OFFPAGE..3
(-2550 5900);
FORCEPROP 2 LAST $XR0 87 
J 0
(-2336 5900);
DISPLAY 0.638298 (-2336 5900);
PAINT MONO (-2336 5900);
FORCEPROP 2 LAST CDS_LIB mstr_standard
J 0
(-2550 5900);
DISPLAY 0.723404 (-2550 5900);
PAINT MONO (-2550 5900);
DISPLAY INVISIBLE (-2550 5900);
FORCEPROP 1 LAST OFFPAGE TRUE
J 0
(-2225 5775);
DISPLAY 0.872340 (-2225 5775);
PAINT GREEN (-2225 5775);
DISPLAY INVISIBLE (-2225 5775);
FORCEPROP 1 LAST COMMENT_BODY TRUE
J 0
(-2600 5800);
DISPLAY 0.872340 (-2600 5800);
PAINT GREEN (-2600 5800);
DISPLAY INVISIBLE (-2600 5800);
FORCEPROP 2 LAST PATH I172
J 0
(-2325 5950);
DISPLAY 1.021277 (-2325 5950);
DISPLAY INVISIBLE (-2325 5950);
FORCEADD TAP..1
(-3275 5775);
FORCEPROP 3 LASTPIN (-3325 5775) SIG_NAME M_B_CPU0_SA_DQ<2>
J 0
(-3315 5785);
DISPLAY 0.659574 (-3315 5785);
PAINT MONO (-3315 5785);
DISPLAY INVISIBLE (-3315 5785);
FORCEPROP 1 LASTPIN (-3325 5775) BN 2
J 0
(-3337 5783);
DISPLAY 0.489362 (-3337 5783);
PAINT GREEN (-3337 5783);
FORCEPROP 2 LAST CDS_LIB mstr_standard
J 0
(-3275 5775);
DISPLAY 0.723404 (-3275 5775);
PAINT MONO (-3275 5775);
DISPLAY INVISIBLE (-3275 5775);
FORCEPROP 1 LAST BODY_TYPE PLUMBING
J 0
(-3275 5825);
DISPLAY 0.872340 (-3275 5825);
PAINT GREEN (-3275 5825);
DISPLAY INVISIBLE (-3275 5825);
FORCEPROP 1 LAST HDL_TAP TRUE
J 0
(-2950 5650);
DISPLAY 0.872340 (-2950 5650);
DISPLAY INVISIBLE (-2950 5650);
FORCEPROP 1 LAST PATH I173
J 0
(-3277 5775);
DISPLAY 0.872340 (-3277 5775);
PAINT GREEN (-3277 5775);
DISPLAY INVISIBLE (-3277 5775);
FORCEADD TAP..1
(-3275 5825);
FORCEPROP 3 LASTPIN (-3325 5825) SIG_NAME M_B_CPU0_SA_DQ<1>
J 0
(-3315 5835);
DISPLAY 0.659574 (-3315 5835);
PAINT MONO (-3315 5835);
DISPLAY INVISIBLE (-3315 5835);
FORCEPROP 1 LASTPIN (-3325 5825) BN 1
J 0
(-3337 5833);
DISPLAY 0.489362 (-3337 5833);
PAINT GREEN (-3337 5833);
FORCEPROP 2 LAST CDS_LIB mstr_standard
J 0
(-3275 5825);
DISPLAY 0.723404 (-3275 5825);
PAINT MONO (-3275 5825);
DISPLAY INVISIBLE (-3275 5825);
FORCEPROP 1 LAST BODY_TYPE PLUMBING
J 0
(-3275 5875);
DISPLAY 0.872340 (-3275 5875);
PAINT GREEN (-3275 5875);
DISPLAY INVISIBLE (-3275 5875);
FORCEPROP 1 LAST HDL_TAP TRUE
J 0
(-2950 5700);
DISPLAY 0.872340 (-2950 5700);
DISPLAY INVISIBLE (-2950 5700);
FORCEPROP 1 LAST PATH I174
J 0
(-3277 5825);
DISPLAY 0.872340 (-3277 5825);
PAINT GREEN (-3277 5825);
DISPLAY INVISIBLE (-3277 5825);
FORCEADD TAP..1
(-3275 5875);
FORCEPROP 3 LASTPIN (-3325 5875) SIG_NAME M_B_CPU0_SA_DQ<0>
J 0
(-3315 5885);
DISPLAY 0.659574 (-3315 5885);
PAINT MONO (-3315 5885);
DISPLAY INVISIBLE (-3315 5885);
FORCEPROP 1 LASTPIN (-3325 5875) BN 0
J 0
(-3337 5883);
DISPLAY 0.489362 (-3337 5883);
PAINT GREEN (-3337 5883);
FORCEPROP 2 LAST CDS_LIB mstr_standard
J 0
(-3275 5875);
DISPLAY 0.723404 (-3275 5875);
PAINT MONO (-3275 5875);
DISPLAY INVISIBLE (-3275 5875);
FORCEPROP 1 LAST BODY_TYPE PLUMBING
J 0
(-3275 5925);
DISPLAY 0.872340 (-3275 5925);
PAINT GREEN (-3275 5925);
DISPLAY INVISIBLE (-3275 5925);
FORCEPROP 1 LAST HDL_TAP TRUE
J 0
(-2950 5750);
DISPLAY 0.872340 (-2950 5750);
DISPLAY INVISIBLE (-2950 5750);
FORCEPROP 1 LAST PATH I175
J 0
(-3277 5875);
DISPLAY 0.872340 (-3277 5875);
PAINT GREEN (-3277 5875);
DISPLAY INVISIBLE (-3277 5875);
FORCEADD TAP..1
(-3275 5675);
FORCEPROP 3 LASTPIN (-3325 5675) SIG_NAME M_B_CPU0_SA_DQ<4>
J 0
(-3315 5685);
DISPLAY 0.659574 (-3315 5685);
PAINT MONO (-3315 5685);
DISPLAY INVISIBLE (-3315 5685);
FORCEPROP 1 LASTPIN (-3325 5675) BN 4
J 0
(-3337 5683);
DISPLAY 0.489362 (-3337 5683);
PAINT GREEN (-3337 5683);
FORCEPROP 2 LAST CDS_LIB mstr_standard
J 0
(-3275 5675);
DISPLAY 0.723404 (-3275 5675);
PAINT MONO (-3275 5675);
DISPLAY INVISIBLE (-3275 5675);
FORCEPROP 1 LAST BODY_TYPE PLUMBING
J 0
(-3275 5725);
DISPLAY 0.872340 (-3275 5725);
PAINT GREEN (-3275 5725);
DISPLAY INVISIBLE (-3275 5725);
FORCEPROP 1 LAST HDL_TAP TRUE
J 0
(-2950 5550);
DISPLAY 0.872340 (-2950 5550);
DISPLAY INVISIBLE (-2950 5550);
FORCEPROP 1 LAST PATH I176
J 0
(-3277 5675);
DISPLAY 0.872340 (-3277 5675);
PAINT GREEN (-3277 5675);
DISPLAY INVISIBLE (-3277 5675);
FORCEADD TAP..1
(-3275 5725);
FORCEPROP 3 LASTPIN (-3325 5725) SIG_NAME M_B_CPU0_SA_DQ<3>
J 0
(-3315 5735);
DISPLAY 0.659574 (-3315 5735);
PAINT MONO (-3315 5735);
DISPLAY INVISIBLE (-3315 5735);
FORCEPROP 1 LASTPIN (-3325 5725) BN 3
J 0
(-3337 5733);
DISPLAY 0.489362 (-3337 5733);
PAINT GREEN (-3337 5733);
FORCEPROP 2 LAST CDS_LIB mstr_standard
J 0
(-3275 5725);
DISPLAY 0.723404 (-3275 5725);
PAINT MONO (-3275 5725);
DISPLAY INVISIBLE (-3275 5725);
FORCEPROP 1 LAST BODY_TYPE PLUMBING
J 0
(-3275 5775);
DISPLAY 0.872340 (-3275 5775);
PAINT GREEN (-3275 5775);
DISPLAY INVISIBLE (-3275 5775);
FORCEPROP 1 LAST HDL_TAP TRUE
J 0
(-2950 5600);
DISPLAY 0.872340 (-2950 5600);
DISPLAY INVISIBLE (-2950 5600);
FORCEPROP 1 LAST PATH I177
J 0
(-3277 5725);
DISPLAY 0.872340 (-3277 5725);
PAINT GREEN (-3277 5725);
DISPLAY INVISIBLE (-3277 5725);
FORCEADD TAP..1
(-3275 5625);
FORCEPROP 3 LASTPIN (-3325 5625) SIG_NAME M_B_CPU0_SA_DQ<5>
J 0
(-3315 5635);
DISPLAY 0.659574 (-3315 5635);
PAINT MONO (-3315 5635);
DISPLAY INVISIBLE (-3315 5635);
FORCEPROP 1 LASTPIN (-3325 5625) BN 5
J 0
(-3337 5633);
DISPLAY 0.489362 (-3337 5633);
PAINT GREEN (-3337 5633);
FORCEPROP 2 LAST CDS_LIB mstr_standard
J 0
(-3275 5625);
DISPLAY 0.723404 (-3275 5625);
PAINT MONO (-3275 5625);
DISPLAY INVISIBLE (-3275 5625);
FORCEPROP 1 LAST BODY_TYPE PLUMBING
J 0
(-3275 5675);
DISPLAY 0.872340 (-3275 5675);
PAINT GREEN (-3275 5675);
DISPLAY INVISIBLE (-3275 5675);
FORCEPROP 1 LAST HDL_TAP TRUE
J 0
(-2950 5500);
DISPLAY 0.872340 (-2950 5500);
DISPLAY INVISIBLE (-2950 5500);
FORCEPROP 1 LAST PATH I178
J 0
(-3277 5625);
DISPLAY 0.872340 (-3277 5625);
PAINT GREEN (-3277 5625);
DISPLAY INVISIBLE (-3277 5625);
FORCEADD TAP..1
(-3275 5575);
FORCEPROP 3 LASTPIN (-3325 5575) SIG_NAME M_B_CPU0_SA_DQ<6>
J 0
(-3315 5585);
DISPLAY 0.659574 (-3315 5585);
PAINT MONO (-3315 5585);
DISPLAY INVISIBLE (-3315 5585);
FORCEPROP 1 LASTPIN (-3325 5575) BN 6
J 0
(-3337 5583);
DISPLAY 0.489362 (-3337 5583);
PAINT GREEN (-3337 5583);
FORCEPROP 2 LAST CDS_LIB mstr_standard
J 0
(-3275 5575);
DISPLAY 0.723404 (-3275 5575);
PAINT MONO (-3275 5575);
DISPLAY INVISIBLE (-3275 5575);
FORCEPROP 1 LAST BODY_TYPE PLUMBING
J 0
(-3275 5625);
DISPLAY 0.872340 (-3275 5625);
PAINT GREEN (-3275 5625);
DISPLAY INVISIBLE (-3275 5625);
FORCEPROP 1 LAST HDL_TAP TRUE
J 0
(-2950 5450);
DISPLAY 0.872340 (-2950 5450);
DISPLAY INVISIBLE (-2950 5450);
FORCEPROP 1 LAST PATH I179
J 0
(-3277 5575);
DISPLAY 0.872340 (-3277 5575);
PAINT GREEN (-3277 5575);
DISPLAY INVISIBLE (-3277 5575);
FORCEADD TAP..1
(-3275 5525);
FORCEPROP 3 LASTPIN (-3325 5525) SIG_NAME M_B_CPU0_SA_DQ<7>
J 0
(-3315 5535);
DISPLAY 0.659574 (-3315 5535);
PAINT MONO (-3315 5535);
DISPLAY INVISIBLE (-3315 5535);
FORCEPROP 1 LASTPIN (-3325 5525) BN 7
J 0
(-3337 5533);
DISPLAY 0.489362 (-3337 5533);
PAINT GREEN (-3337 5533);
FORCEPROP 2 LAST CDS_LIB mstr_standard
J 0
(-3275 5525);
DISPLAY 0.723404 (-3275 5525);
PAINT MONO (-3275 5525);
DISPLAY INVISIBLE (-3275 5525);
FORCEPROP 1 LAST BODY_TYPE PLUMBING
J 0
(-3275 5575);
DISPLAY 0.872340 (-3275 5575);
PAINT GREEN (-3275 5575);
DISPLAY INVISIBLE (-3275 5575);
FORCEPROP 1 LAST HDL_TAP TRUE
J 0
(-2950 5400);
DISPLAY 0.872340 (-2950 5400);
DISPLAY INVISIBLE (-2950 5400);
FORCEPROP 1 LAST PATH I180
J 0
(-3277 5525);
DISPLAY 0.872340 (-3277 5525);
PAINT GREEN (-3277 5525);
DISPLAY INVISIBLE (-3277 5525);
FORCEADD TAP..1
(-3275 5425);
FORCEPROP 3 LASTPIN (-3325 5425) SIG_NAME M_B_CPU0_SA_DQ<8>
J 0
(-3315 5435);
DISPLAY 0.659574 (-3315 5435);
PAINT MONO (-3315 5435);
DISPLAY INVISIBLE (-3315 5435);
FORCEPROP 1 LASTPIN (-3325 5425) BN 8
J 0
(-3337 5433);
DISPLAY 0.489362 (-3337 5433);
PAINT GREEN (-3337 5433);
FORCEPROP 2 LAST CDS_LIB mstr_standard
J 0
(-3275 5425);
DISPLAY 0.723404 (-3275 5425);
PAINT MONO (-3275 5425);
DISPLAY INVISIBLE (-3275 5425);
FORCEPROP 1 LAST BODY_TYPE PLUMBING
J 0
(-3275 5475);
DISPLAY 0.872340 (-3275 5475);
PAINT GREEN (-3275 5475);
DISPLAY INVISIBLE (-3275 5475);
FORCEPROP 1 LAST HDL_TAP TRUE
J 0
(-2950 5300);
DISPLAY 0.872340 (-2950 5300);
DISPLAY INVISIBLE (-2950 5300);
FORCEPROP 1 LAST PATH I181
J 0
(-3277 5425);
DISPLAY 0.872340 (-3277 5425);
PAINT GREEN (-3277 5425);
DISPLAY INVISIBLE (-3277 5425);
FORCEADD TAP..1
(-3275 5275);
FORCEPROP 3 LASTPIN (-3325 5275) SIG_NAME M_B_CPU0_SA_DQ<11>
J 0
(-3315 5285);
DISPLAY 0.659574 (-3315 5285);
PAINT MONO (-3315 5285);
DISPLAY INVISIBLE (-3315 5285);
FORCEPROP 1 LASTPIN (-3325 5275) BN 11
J 0
(-3337 5283);
DISPLAY 0.489362 (-3337 5283);
PAINT GREEN (-3337 5283);
FORCEPROP 2 LAST CDS_LIB mstr_standard
J 0
(-3275 5275);
DISPLAY 0.723404 (-3275 5275);
PAINT MONO (-3275 5275);
DISPLAY INVISIBLE (-3275 5275);
FORCEPROP 1 LAST BODY_TYPE PLUMBING
J 0
(-3275 5325);
DISPLAY 0.872340 (-3275 5325);
PAINT GREEN (-3275 5325);
DISPLAY INVISIBLE (-3275 5325);
FORCEPROP 1 LAST HDL_TAP TRUE
J 0
(-2950 5150);
DISPLAY 0.872340 (-2950 5150);
DISPLAY INVISIBLE (-2950 5150);
FORCEPROP 1 LAST PATH I182
J 0
(-3277 5275);
DISPLAY 0.872340 (-3277 5275);
PAINT GREEN (-3277 5275);
DISPLAY INVISIBLE (-3277 5275);
FORCEADD TAP..1
(-3275 5325);
FORCEPROP 3 LASTPIN (-3325 5325) SIG_NAME M_B_CPU0_SA_DQ<10>
J 0
(-3315 5335);
DISPLAY 0.659574 (-3315 5335);
PAINT MONO (-3315 5335);
DISPLAY INVISIBLE (-3315 5335);
FORCEPROP 1 LASTPIN (-3325 5325) BN 10
J 0
(-3337 5333);
DISPLAY 0.489362 (-3337 5333);
PAINT GREEN (-3337 5333);
FORCEPROP 2 LAST CDS_LIB mstr_standard
J 0
(-3275 5325);
DISPLAY 0.723404 (-3275 5325);
PAINT MONO (-3275 5325);
DISPLAY INVISIBLE (-3275 5325);
FORCEPROP 1 LAST BODY_TYPE PLUMBING
J 0
(-3275 5375);
DISPLAY 0.872340 (-3275 5375);
PAINT GREEN (-3275 5375);
DISPLAY INVISIBLE (-3275 5375);
FORCEPROP 1 LAST HDL_TAP TRUE
J 0
(-2950 5200);
DISPLAY 0.872340 (-2950 5200);
DISPLAY INVISIBLE (-2950 5200);
FORCEPROP 1 LAST PATH I183
J 0
(-3277 5325);
DISPLAY 0.872340 (-3277 5325);
PAINT GREEN (-3277 5325);
DISPLAY INVISIBLE (-3277 5325);
FORCEADD TAP..1
(-3275 5375);
FORCEPROP 3 LASTPIN (-3325 5375) SIG_NAME M_B_CPU0_SA_DQ<9>
J 0
(-3315 5385);
DISPLAY 0.659574 (-3315 5385);
PAINT MONO (-3315 5385);
DISPLAY INVISIBLE (-3315 5385);
FORCEPROP 1 LASTPIN (-3325 5375) BN 9
J 0
(-3337 5383);
DISPLAY 0.489362 (-3337 5383);
PAINT GREEN (-3337 5383);
FORCEPROP 2 LAST CDS_LIB mstr_standard
J 0
(-3275 5375);
DISPLAY 0.723404 (-3275 5375);
PAINT MONO (-3275 5375);
DISPLAY INVISIBLE (-3275 5375);
FORCEPROP 1 LAST BODY_TYPE PLUMBING
J 0
(-3275 5425);
DISPLAY 0.872340 (-3275 5425);
PAINT GREEN (-3275 5425);
DISPLAY INVISIBLE (-3275 5425);
FORCEPROP 1 LAST HDL_TAP TRUE
J 0
(-2950 5250);
DISPLAY 0.872340 (-2950 5250);
DISPLAY INVISIBLE (-2950 5250);
FORCEPROP 1 LAST PATH I184
J 0
(-3277 5375);
DISPLAY 0.872340 (-3277 5375);
PAINT GREEN (-3277 5375);
DISPLAY INVISIBLE (-3277 5375);
FORCEADD TAP..1
(-3275 5225);
FORCEPROP 3 LASTPIN (-3325 5225) SIG_NAME M_B_CPU0_SA_DQ<12>
J 0
(-3315 5235);
DISPLAY 0.659574 (-3315 5235);
PAINT MONO (-3315 5235);
DISPLAY INVISIBLE (-3315 5235);
FORCEPROP 1 LASTPIN (-3325 5225) BN 12
J 0
(-3337 5233);
DISPLAY 0.489362 (-3337 5233);
PAINT GREEN (-3337 5233);
FORCEPROP 2 LAST CDS_LIB mstr_standard
J 0
(-3275 5225);
DISPLAY 0.723404 (-3275 5225);
PAINT MONO (-3275 5225);
DISPLAY INVISIBLE (-3275 5225);
FORCEPROP 1 LAST BODY_TYPE PLUMBING
J 0
(-3275 5275);
DISPLAY 0.872340 (-3275 5275);
PAINT GREEN (-3275 5275);
DISPLAY INVISIBLE (-3275 5275);
FORCEPROP 1 LAST HDL_TAP TRUE
J 0
(-2950 5100);
DISPLAY 0.872340 (-2950 5100);
DISPLAY INVISIBLE (-2950 5100);
FORCEPROP 1 LAST PATH I185
J 0
(-3277 5225);
DISPLAY 0.872340 (-3277 5225);
PAINT GREEN (-3277 5225);
DISPLAY INVISIBLE (-3277 5225);
FORCEADD TAP..1
(-3275 5175);
FORCEPROP 3 LASTPIN (-3325 5175) SIG_NAME M_B_CPU0_SA_DQ<13>
J 0
(-3315 5185);
DISPLAY 0.659574 (-3315 5185);
PAINT MONO (-3315 5185);
DISPLAY INVISIBLE (-3315 5185);
FORCEPROP 1 LASTPIN (-3325 5175) BN 13
J 0
(-3337 5183);
DISPLAY 0.489362 (-3337 5183);
PAINT GREEN (-3337 5183);
FORCEPROP 2 LAST CDS_LIB mstr_standard
J 0
(-3275 5175);
DISPLAY 0.723404 (-3275 5175);
PAINT MONO (-3275 5175);
DISPLAY INVISIBLE (-3275 5175);
FORCEPROP 1 LAST BODY_TYPE PLUMBING
J 0
(-3275 5225);
DISPLAY 0.872340 (-3275 5225);
PAINT GREEN (-3275 5225);
DISPLAY INVISIBLE (-3275 5225);
FORCEPROP 1 LAST HDL_TAP TRUE
J 0
(-2950 5050);
DISPLAY 0.872340 (-2950 5050);
DISPLAY INVISIBLE (-2950 5050);
FORCEPROP 1 LAST PATH I186
J 0
(-3277 5175);
DISPLAY 0.872340 (-3277 5175);
PAINT GREEN (-3277 5175);
DISPLAY INVISIBLE (-3277 5175);
FORCEADD TAP..1
(-3275 5125);
FORCEPROP 3 LASTPIN (-3325 5125) SIG_NAME M_B_CPU0_SA_DQ<14>
J 0
(-3315 5135);
DISPLAY 0.659574 (-3315 5135);
PAINT MONO (-3315 5135);
DISPLAY INVISIBLE (-3315 5135);
FORCEPROP 1 LASTPIN (-3325 5125) BN 14
J 0
(-3337 5133);
DISPLAY 0.489362 (-3337 5133);
PAINT GREEN (-3337 5133);
FORCEPROP 2 LAST CDS_LIB mstr_standard
J 0
(-3275 5125);
DISPLAY 0.723404 (-3275 5125);
PAINT MONO (-3275 5125);
DISPLAY INVISIBLE (-3275 5125);
FORCEPROP 1 LAST BODY_TYPE PLUMBING
J 0
(-3275 5175);
DISPLAY 0.872340 (-3275 5175);
PAINT GREEN (-3275 5175);
DISPLAY INVISIBLE (-3275 5175);
FORCEPROP 1 LAST HDL_TAP TRUE
J 0
(-2950 5000);
DISPLAY 0.872340 (-2950 5000);
DISPLAY INVISIBLE (-2950 5000);
FORCEPROP 1 LAST PATH I187
J 0
(-3277 5125);
DISPLAY 0.872340 (-3277 5125);
PAINT GREEN (-3277 5125);
DISPLAY INVISIBLE (-3277 5125);
FORCEADD TAP..1
(-3275 5075);
FORCEPROP 3 LASTPIN (-3325 5075) SIG_NAME M_B_CPU0_SA_DQ<15>
J 0
(-3315 5085);
DISPLAY 0.659574 (-3315 5085);
PAINT MONO (-3315 5085);
DISPLAY INVISIBLE (-3315 5085);
FORCEPROP 1 LASTPIN (-3325 5075) BN 15
J 0
(-3337 5083);
DISPLAY 0.489362 (-3337 5083);
PAINT GREEN (-3337 5083);
FORCEPROP 2 LAST CDS_LIB mstr_standard
J 0
(-3275 5075);
DISPLAY 0.723404 (-3275 5075);
PAINT MONO (-3275 5075);
DISPLAY INVISIBLE (-3275 5075);
FORCEPROP 1 LAST BODY_TYPE PLUMBING
J 0
(-3275 5125);
DISPLAY 0.872340 (-3275 5125);
PAINT GREEN (-3275 5125);
DISPLAY INVISIBLE (-3275 5125);
FORCEPROP 1 LAST HDL_TAP TRUE
J 0
(-2950 4950);
DISPLAY 0.872340 (-2950 4950);
DISPLAY INVISIBLE (-2950 4950);
FORCEPROP 1 LAST PATH I188
J 0
(-3277 5075);
DISPLAY 0.872340 (-3277 5075);
PAINT GREEN (-3277 5075);
DISPLAY INVISIBLE (-3277 5075);
FORCEADD TAP..1
(-3275 4975);
FORCEPROP 3 LASTPIN (-3325 4975) SIG_NAME M_B_CPU0_SA_DQ<16>
J 0
(-3315 4985);
DISPLAY 0.659574 (-3315 4985);
PAINT MONO (-3315 4985);
DISPLAY INVISIBLE (-3315 4985);
FORCEPROP 1 LASTPIN (-3325 4975) BN 16
J 0
(-3337 4983);
DISPLAY 0.489362 (-3337 4983);
PAINT GREEN (-3337 4983);
FORCEPROP 2 LAST CDS_LIB mstr_standard
J 0
(-3275 4975);
DISPLAY 0.723404 (-3275 4975);
PAINT MONO (-3275 4975);
DISPLAY INVISIBLE (-3275 4975);
FORCEPROP 1 LAST BODY_TYPE PLUMBING
J 0
(-3275 5025);
DISPLAY 0.872340 (-3275 5025);
PAINT GREEN (-3275 5025);
DISPLAY INVISIBLE (-3275 5025);
FORCEPROP 1 LAST HDL_TAP TRUE
J 0
(-2950 4850);
DISPLAY 0.872340 (-2950 4850);
DISPLAY INVISIBLE (-2950 4850);
FORCEPROP 1 LAST PATH I189
J 0
(-3277 4975);
DISPLAY 0.872340 (-3277 4975);
PAINT GREEN (-3277 4975);
DISPLAY INVISIBLE (-3277 4975);
FORCEADD TAP..1
(-3275 4925);
FORCEPROP 3 LASTPIN (-3325 4925) SIG_NAME M_B_CPU0_SA_DQ<17>
J 0
(-3315 4935);
DISPLAY 0.659574 (-3315 4935);
PAINT MONO (-3315 4935);
DISPLAY INVISIBLE (-3315 4935);
FORCEPROP 1 LASTPIN (-3325 4925) BN 17
J 0
(-3337 4933);
DISPLAY 0.489362 (-3337 4933);
PAINT GREEN (-3337 4933);
FORCEPROP 2 LAST CDS_LIB mstr_standard
J 0
(-3275 4925);
DISPLAY 0.723404 (-3275 4925);
PAINT MONO (-3275 4925);
DISPLAY INVISIBLE (-3275 4925);
FORCEPROP 1 LAST BODY_TYPE PLUMBING
J 0
(-3275 4975);
DISPLAY 0.872340 (-3275 4975);
PAINT GREEN (-3275 4975);
DISPLAY INVISIBLE (-3275 4975);
FORCEPROP 1 LAST HDL_TAP TRUE
J 0
(-2950 4800);
DISPLAY 0.872340 (-2950 4800);
DISPLAY INVISIBLE (-2950 4800);
FORCEPROP 1 LAST PATH I190
J 0
(-3277 4925);
DISPLAY 0.872340 (-3277 4925);
PAINT GREEN (-3277 4925);
DISPLAY INVISIBLE (-3277 4925);
FORCEADD TAP..1
(-3275 4875);
FORCEPROP 3 LASTPIN (-3325 4875) SIG_NAME M_B_CPU0_SA_DQ<18>
J 0
(-3315 4885);
DISPLAY 0.659574 (-3315 4885);
PAINT MONO (-3315 4885);
DISPLAY INVISIBLE (-3315 4885);
FORCEPROP 1 LASTPIN (-3325 4875) BN 18
J 0
(-3337 4883);
DISPLAY 0.489362 (-3337 4883);
PAINT GREEN (-3337 4883);
FORCEPROP 2 LAST CDS_LIB mstr_standard
J 0
(-3275 4875);
DISPLAY 0.723404 (-3275 4875);
PAINT MONO (-3275 4875);
DISPLAY INVISIBLE (-3275 4875);
FORCEPROP 1 LAST BODY_TYPE PLUMBING
J 0
(-3275 4925);
DISPLAY 0.872340 (-3275 4925);
PAINT GREEN (-3275 4925);
DISPLAY INVISIBLE (-3275 4925);
FORCEPROP 1 LAST HDL_TAP TRUE
J 0
(-2950 4750);
DISPLAY 0.872340 (-2950 4750);
DISPLAY INVISIBLE (-2950 4750);
FORCEPROP 1 LAST PATH I191
J 0
(-3277 4875);
DISPLAY 0.872340 (-3277 4875);
PAINT GREEN (-3277 4875);
DISPLAY INVISIBLE (-3277 4875);
FORCEADD TAP..1
(-3275 4775);
FORCEPROP 3 LASTPIN (-3325 4775) SIG_NAME M_B_CPU0_SA_DQ<20>
J 0
(-3315 4785);
DISPLAY 0.659574 (-3315 4785);
PAINT MONO (-3315 4785);
DISPLAY INVISIBLE (-3315 4785);
FORCEPROP 1 LASTPIN (-3325 4775) BN 20
J 0
(-3337 4783);
DISPLAY 0.489362 (-3337 4783);
PAINT GREEN (-3337 4783);
FORCEPROP 2 LAST CDS_LIB mstr_standard
J 0
(-3275 4775);
DISPLAY 0.723404 (-3275 4775);
PAINT MONO (-3275 4775);
DISPLAY INVISIBLE (-3275 4775);
FORCEPROP 1 LAST BODY_TYPE PLUMBING
J 0
(-3275 4825);
DISPLAY 0.872340 (-3275 4825);
PAINT GREEN (-3275 4825);
DISPLAY INVISIBLE (-3275 4825);
FORCEPROP 1 LAST HDL_TAP TRUE
J 0
(-2950 4650);
DISPLAY 0.872340 (-2950 4650);
DISPLAY INVISIBLE (-2950 4650);
FORCEPROP 1 LAST PATH I192
J 0
(-3277 4775);
DISPLAY 0.872340 (-3277 4775);
PAINT GREEN (-3277 4775);
DISPLAY INVISIBLE (-3277 4775);
FORCEADD TAP..1
(-3275 4825);
FORCEPROP 3 LASTPIN (-3325 4825) SIG_NAME M_B_CPU0_SA_DQ<19>
J 0
(-3315 4835);
DISPLAY 0.659574 (-3315 4835);
PAINT MONO (-3315 4835);
DISPLAY INVISIBLE (-3315 4835);
FORCEPROP 1 LASTPIN (-3325 4825) BN 19
J 0
(-3337 4833);
DISPLAY 0.489362 (-3337 4833);
PAINT GREEN (-3337 4833);
FORCEPROP 2 LAST CDS_LIB mstr_standard
J 0
(-3275 4825);
DISPLAY 0.723404 (-3275 4825);
PAINT MONO (-3275 4825);
DISPLAY INVISIBLE (-3275 4825);
FORCEPROP 1 LAST BODY_TYPE PLUMBING
J 0
(-3275 4875);
DISPLAY 0.872340 (-3275 4875);
PAINT GREEN (-3275 4875);
DISPLAY INVISIBLE (-3275 4875);
FORCEPROP 1 LAST HDL_TAP TRUE
J 0
(-2950 4700);
DISPLAY 0.872340 (-2950 4700);
DISPLAY INVISIBLE (-2950 4700);
FORCEPROP 1 LAST PATH I193
J 0
(-3277 4825);
DISPLAY 0.872340 (-3277 4825);
PAINT GREEN (-3277 4825);
DISPLAY INVISIBLE (-3277 4825);
FORCEADD TAP..1
(-3275 4725);
FORCEPROP 3 LASTPIN (-3325 4725) SIG_NAME M_B_CPU0_SA_DQ<21>
J 0
(-3315 4735);
DISPLAY 0.659574 (-3315 4735);
PAINT MONO (-3315 4735);
DISPLAY INVISIBLE (-3315 4735);
FORCEPROP 1 LASTPIN (-3325 4725) BN 21
J 0
(-3337 4733);
DISPLAY 0.489362 (-3337 4733);
PAINT GREEN (-3337 4733);
FORCEPROP 2 LAST CDS_LIB mstr_standard
J 0
(-3275 4725);
DISPLAY 0.723404 (-3275 4725);
PAINT MONO (-3275 4725);
DISPLAY INVISIBLE (-3275 4725);
FORCEPROP 1 LAST BODY_TYPE PLUMBING
J 0
(-3275 4775);
DISPLAY 0.872340 (-3275 4775);
PAINT GREEN (-3275 4775);
DISPLAY INVISIBLE (-3275 4775);
FORCEPROP 1 LAST HDL_TAP TRUE
J 0
(-2950 4600);
DISPLAY 0.872340 (-2950 4600);
DISPLAY INVISIBLE (-2950 4600);
FORCEPROP 1 LAST PATH I194
J 0
(-3277 4725);
DISPLAY 0.872340 (-3277 4725);
PAINT GREEN (-3277 4725);
DISPLAY INVISIBLE (-3277 4725);
FORCEADD TAP..1
(-3275 4675);
FORCEPROP 3 LASTPIN (-3325 4675) SIG_NAME M_B_CPU0_SA_DQ<22>
J 0
(-3315 4685);
DISPLAY 0.659574 (-3315 4685);
PAINT MONO (-3315 4685);
DISPLAY INVISIBLE (-3315 4685);
FORCEPROP 1 LASTPIN (-3325 4675) BN 22
J 0
(-3337 4683);
DISPLAY 0.489362 (-3337 4683);
PAINT GREEN (-3337 4683);
FORCEPROP 2 LAST CDS_LIB mstr_standard
J 0
(-3275 4675);
DISPLAY 0.723404 (-3275 4675);
PAINT MONO (-3275 4675);
DISPLAY INVISIBLE (-3275 4675);
FORCEPROP 1 LAST BODY_TYPE PLUMBING
J 0
(-3275 4725);
DISPLAY 0.872340 (-3275 4725);
PAINT GREEN (-3275 4725);
DISPLAY INVISIBLE (-3275 4725);
FORCEPROP 1 LAST HDL_TAP TRUE
J 0
(-2950 4550);
DISPLAY 0.872340 (-2950 4550);
DISPLAY INVISIBLE (-2950 4550);
FORCEPROP 1 LAST PATH I195
J 0
(-3277 4675);
DISPLAY 0.872340 (-3277 4675);
PAINT GREEN (-3277 4675);
DISPLAY INVISIBLE (-3277 4675);
FORCEADD TAP..1
(-3275 4625);
FORCEPROP 3 LASTPIN (-3325 4625) SIG_NAME M_B_CPU0_SA_DQ<23>
J 0
(-3315 4635);
DISPLAY 0.659574 (-3315 4635);
PAINT MONO (-3315 4635);
DISPLAY INVISIBLE (-3315 4635);
FORCEPROP 1 LASTPIN (-3325 4625) BN 23
J 0
(-3337 4633);
DISPLAY 0.489362 (-3337 4633);
PAINT GREEN (-3337 4633);
FORCEPROP 2 LAST CDS_LIB mstr_standard
J 0
(-3275 4625);
DISPLAY 0.723404 (-3275 4625);
PAINT MONO (-3275 4625);
DISPLAY INVISIBLE (-3275 4625);
FORCEPROP 1 LAST BODY_TYPE PLUMBING
J 0
(-3275 4675);
DISPLAY 0.872340 (-3275 4675);
PAINT GREEN (-3275 4675);
DISPLAY INVISIBLE (-3275 4675);
FORCEPROP 1 LAST HDL_TAP TRUE
J 0
(-2950 4500);
DISPLAY 0.872340 (-2950 4500);
DISPLAY INVISIBLE (-2950 4500);
FORCEPROP 1 LAST PATH I196
J 0
(-3277 4625);
DISPLAY 0.872340 (-3277 4625);
PAINT GREEN (-3277 4625);
DISPLAY INVISIBLE (-3277 4625);
FORCEADD TAP..1
(-3275 4525);
FORCEPROP 3 LASTPIN (-3325 4525) SIG_NAME M_B_CPU0_SA_DQ<24>
J 0
(-3315 4535);
DISPLAY 0.659574 (-3315 4535);
PAINT MONO (-3315 4535);
DISPLAY INVISIBLE (-3315 4535);
FORCEPROP 1 LASTPIN (-3325 4525) BN 24
J 0
(-3337 4533);
DISPLAY 0.489362 (-3337 4533);
PAINT GREEN (-3337 4533);
FORCEPROP 2 LAST CDS_LIB mstr_standard
J 0
(-3275 4525);
DISPLAY 0.723404 (-3275 4525);
PAINT MONO (-3275 4525);
DISPLAY INVISIBLE (-3275 4525);
FORCEPROP 1 LAST BODY_TYPE PLUMBING
J 0
(-3275 4575);
DISPLAY 0.872340 (-3275 4575);
PAINT GREEN (-3275 4575);
DISPLAY INVISIBLE (-3275 4575);
FORCEPROP 1 LAST HDL_TAP TRUE
J 0
(-2950 4400);
DISPLAY 0.872340 (-2950 4400);
DISPLAY INVISIBLE (-2950 4400);
FORCEPROP 1 LAST PATH I197
J 0
(-3277 4525);
DISPLAY 0.872340 (-3277 4525);
PAINT GREEN (-3277 4525);
DISPLAY INVISIBLE (-3277 4525);
FORCEADD TAP..1
(-3275 4475);
FORCEPROP 3 LASTPIN (-3325 4475) SIG_NAME M_B_CPU0_SA_DQ<25>
J 0
(-3315 4485);
DISPLAY 0.659574 (-3315 4485);
PAINT MONO (-3315 4485);
DISPLAY INVISIBLE (-3315 4485);
FORCEPROP 1 LASTPIN (-3325 4475) BN 25
J 0
(-3337 4483);
DISPLAY 0.489362 (-3337 4483);
PAINT GREEN (-3337 4483);
FORCEPROP 2 LAST CDS_LIB mstr_standard
J 0
(-3275 4475);
DISPLAY 0.723404 (-3275 4475);
PAINT MONO (-3275 4475);
DISPLAY INVISIBLE (-3275 4475);
FORCEPROP 1 LAST BODY_TYPE PLUMBING
J 0
(-3275 4525);
DISPLAY 0.872340 (-3275 4525);
PAINT GREEN (-3275 4525);
DISPLAY INVISIBLE (-3275 4525);
FORCEPROP 1 LAST HDL_TAP TRUE
J 0
(-2950 4350);
DISPLAY 0.872340 (-2950 4350);
DISPLAY INVISIBLE (-2950 4350);
FORCEPROP 1 LAST PATH I198
J 0
(-3277 4475);
DISPLAY 0.872340 (-3277 4475);
PAINT GREEN (-3277 4475);
DISPLAY INVISIBLE (-3277 4475);
FORCEADD TAP..1
(-3275 4425);
FORCEPROP 3 LASTPIN (-3325 4425) SIG_NAME M_B_CPU0_SA_DQ<26>
J 0
(-3315 4435);
DISPLAY 0.659574 (-3315 4435);
PAINT MONO (-3315 4435);
DISPLAY INVISIBLE (-3315 4435);
FORCEPROP 1 LASTPIN (-3325 4425) BN 26
J 0
(-3337 4433);
DISPLAY 0.489362 (-3337 4433);
PAINT GREEN (-3337 4433);
FORCEPROP 2 LAST CDS_LIB mstr_standard
J 0
(-3275 4425);
DISPLAY 0.723404 (-3275 4425);
PAINT MONO (-3275 4425);
DISPLAY INVISIBLE (-3275 4425);
FORCEPROP 1 LAST BODY_TYPE PLUMBING
J 0
(-3275 4475);
DISPLAY 0.872340 (-3275 4475);
PAINT GREEN (-3275 4475);
DISPLAY INVISIBLE (-3275 4475);
FORCEPROP 1 LAST HDL_TAP TRUE
J 0
(-2950 4300);
DISPLAY 0.872340 (-2950 4300);
DISPLAY INVISIBLE (-2950 4300);
FORCEPROP 1 LAST PATH I199
J 0
(-3277 4425);
DISPLAY 0.872340 (-3277 4425);
PAINT GREEN (-3277 4425);
DISPLAY INVISIBLE (-3277 4425);
FORCEADD TAP..1
(-3275 4375);
FORCEPROP 3 LASTPIN (-3325 4375) SIG_NAME M_B_CPU0_SA_DQ<27>
J 0
(-3315 4385);
DISPLAY 0.659574 (-3315 4385);
PAINT MONO (-3315 4385);
DISPLAY INVISIBLE (-3315 4385);
FORCEPROP 1 LASTPIN (-3325 4375) BN 27
J 0
(-3337 4383);
DISPLAY 0.489362 (-3337 4383);
PAINT GREEN (-3337 4383);
FORCEPROP 2 LAST CDS_LIB mstr_standard
J 0
(-3275 4375);
DISPLAY 0.723404 (-3275 4375);
PAINT MONO (-3275 4375);
DISPLAY INVISIBLE (-3275 4375);
FORCEPROP 1 LAST BODY_TYPE PLUMBING
J 0
(-3275 4425);
DISPLAY 0.872340 (-3275 4425);
PAINT GREEN (-3275 4425);
DISPLAY INVISIBLE (-3275 4425);
FORCEPROP 1 LAST HDL_TAP TRUE
J 0
(-2950 4250);
DISPLAY 0.872340 (-2950 4250);
DISPLAY INVISIBLE (-2950 4250);
FORCEPROP 1 LAST PATH I200
J 0
(-3277 4375);
DISPLAY 0.872340 (-3277 4375);
PAINT GREEN (-3277 4375);
DISPLAY INVISIBLE (-3277 4375);
FORCEADD TAP..1
(-3275 4275);
FORCEPROP 3 LASTPIN (-3325 4275) SIG_NAME M_B_CPU0_SA_DQ<29>
J 0
(-3315 4285);
DISPLAY 0.659574 (-3315 4285);
PAINT MONO (-3315 4285);
DISPLAY INVISIBLE (-3315 4285);
FORCEPROP 1 LASTPIN (-3325 4275) BN 29
J 0
(-3337 4283);
DISPLAY 0.489362 (-3337 4283);
PAINT GREEN (-3337 4283);
FORCEPROP 2 LAST CDS_LIB mstr_standard
J 0
(-3275 4275);
DISPLAY 0.723404 (-3275 4275);
PAINT MONO (-3275 4275);
DISPLAY INVISIBLE (-3275 4275);
FORCEPROP 1 LAST BODY_TYPE PLUMBING
J 0
(-3275 4325);
DISPLAY 0.872340 (-3275 4325);
PAINT GREEN (-3275 4325);
DISPLAY INVISIBLE (-3275 4325);
FORCEPROP 1 LAST HDL_TAP TRUE
J 0
(-2950 4150);
DISPLAY 0.872340 (-2950 4150);
DISPLAY INVISIBLE (-2950 4150);
FORCEPROP 1 LAST PATH I201
J 0
(-3277 4275);
DISPLAY 0.872340 (-3277 4275);
PAINT GREEN (-3277 4275);
DISPLAY INVISIBLE (-3277 4275);
FORCEADD TAP..1
(-3275 4225);
FORCEPROP 3 LASTPIN (-3325 4225) SIG_NAME M_B_CPU0_SA_DQ<30>
J 0
(-3315 4235);
DISPLAY 0.659574 (-3315 4235);
PAINT MONO (-3315 4235);
DISPLAY INVISIBLE (-3315 4235);
FORCEPROP 1 LASTPIN (-3325 4225) BN 30
J 0
(-3337 4233);
DISPLAY 0.489362 (-3337 4233);
PAINT GREEN (-3337 4233);
FORCEPROP 2 LAST CDS_LIB mstr_standard
J 0
(-3275 4225);
DISPLAY 0.723404 (-3275 4225);
PAINT MONO (-3275 4225);
DISPLAY INVISIBLE (-3275 4225);
FORCEPROP 1 LAST BODY_TYPE PLUMBING
J 0
(-3275 4275);
DISPLAY 0.872340 (-3275 4275);
PAINT GREEN (-3275 4275);
DISPLAY INVISIBLE (-3275 4275);
FORCEPROP 1 LAST HDL_TAP TRUE
J 0
(-2950 4100);
DISPLAY 0.872340 (-2950 4100);
DISPLAY INVISIBLE (-2950 4100);
FORCEPROP 1 LAST PATH I202
J 0
(-3277 4225);
DISPLAY 0.872340 (-3277 4225);
PAINT GREEN (-3277 4225);
DISPLAY INVISIBLE (-3277 4225);
FORCEADD TAP..1
(-3275 4325);
FORCEPROP 3 LASTPIN (-3325 4325) SIG_NAME M_B_CPU0_SA_DQ<28>
J 0
(-3315 4335);
DISPLAY 0.659574 (-3315 4335);
PAINT MONO (-3315 4335);
DISPLAY INVISIBLE (-3315 4335);
FORCEPROP 1 LASTPIN (-3325 4325) BN 28
J 0
(-3337 4333);
DISPLAY 0.489362 (-3337 4333);
PAINT GREEN (-3337 4333);
FORCEPROP 2 LAST CDS_LIB mstr_standard
J 0
(-3275 4325);
DISPLAY 0.723404 (-3275 4325);
PAINT MONO (-3275 4325);
DISPLAY INVISIBLE (-3275 4325);
FORCEPROP 1 LAST BODY_TYPE PLUMBING
J 0
(-3275 4375);
DISPLAY 0.872340 (-3275 4375);
PAINT GREEN (-3275 4375);
DISPLAY INVISIBLE (-3275 4375);
FORCEPROP 1 LAST HDL_TAP TRUE
J 0
(-2950 4200);
DISPLAY 0.872340 (-2950 4200);
DISPLAY INVISIBLE (-2950 4200);
FORCEPROP 1 LAST PATH I203
J 0
(-3277 4325);
DISPLAY 0.872340 (-3277 4325);
PAINT GREEN (-3277 4325);
DISPLAY INVISIBLE (-3277 4325);
FORCEADD TAP..1
(-3275 4175);
FORCEPROP 3 LASTPIN (-3325 4175) SIG_NAME M_B_CPU0_SA_DQ<31>
J 0
(-3315 4185);
DISPLAY 0.659574 (-3315 4185);
PAINT MONO (-3315 4185);
DISPLAY INVISIBLE (-3315 4185);
FORCEPROP 1 LASTPIN (-3325 4175) BN 31
J 0
(-3337 4183);
DISPLAY 0.489362 (-3337 4183);
PAINT GREEN (-3337 4183);
FORCEPROP 2 LAST CDS_LIB mstr_standard
J 0
(-3275 4175);
DISPLAY 0.723404 (-3275 4175);
PAINT MONO (-3275 4175);
DISPLAY INVISIBLE (-3275 4175);
FORCEPROP 1 LAST BODY_TYPE PLUMBING
J 0
(-3275 4225);
DISPLAY 0.872340 (-3275 4225);
PAINT GREEN (-3275 4225);
DISPLAY INVISIBLE (-3275 4225);
FORCEPROP 1 LAST HDL_TAP TRUE
J 0
(-2950 4050);
DISPLAY 0.872340 (-2950 4050);
DISPLAY INVISIBLE (-2950 4050);
FORCEPROP 1 LAST PATH I204
J 0
(-3277 4175);
DISPLAY 0.872340 (-3277 4175);
PAINT GREEN (-3277 4175);
DISPLAY INVISIBLE (-3277 4175);
FORCEADD OFFPAGE..3
(-2550 4100);
FORCEPROP 2 LAST $XR0 87 
J 0
(-2336 4100);
DISPLAY 0.638298 (-2336 4100);
PAINT MONO (-2336 4100);
FORCEPROP 2 LAST CDS_LIB mstr_standard
J 0
(-2550 4100);
DISPLAY 0.723404 (-2550 4100);
PAINT MONO (-2550 4100);
DISPLAY INVISIBLE (-2550 4100);
FORCEPROP 1 LAST OFFPAGE TRUE
J 0
(-2225 3975);
DISPLAY 0.872340 (-2225 3975);
PAINT GREEN (-2225 3975);
DISPLAY INVISIBLE (-2225 3975);
FORCEPROP 1 LAST COMMENT_BODY TRUE
J 0
(-2600 4000);
DISPLAY 0.872340 (-2600 4000);
PAINT GREEN (-2600 4000);
DISPLAY INVISIBLE (-2600 4000);
FORCEPROP 2 LAST PATH I205
J 0
(-2325 4150);
DISPLAY 1.021277 (-2325 4150);
DISPLAY INVISIBLE (-2325 4150);
FORCEADD OFFPAGE..6
R 2
(-2675 2325);
FORCEPROP 2 LAST $XR0 87 
J 0
(-2461 2325);
DISPLAY 0.638298 (-2461 2325);
PAINT MONO (-2461 2325);
FORCEPROP 2 LAST CDS_LIB mstr_standard
J 2
(-2675 2325);
DISPLAY 0.723404 (-2675 2325);
PAINT MONO (-2675 2325);
DISPLAY INVISIBLE (-2675 2325);
FORCEPROP 1 LAST OFFPAGE TRUE
J 2
(-3000 2200);
DISPLAY 0.872340 (-3000 2200);
PAINT GREEN (-3000 2200);
DISPLAY INVISIBLE (-3000 2200);
FORCEPROP 1 LAST COMMENT_BODY TRUE
J 2
(-2775 2250);
DISPLAY 0.872340 (-2775 2250);
PAINT GREEN (-2775 2250);
DISPLAY INVISIBLE (-2775 2250);
FORCEPROP 2 LAST PATH I206
J 0
(-2450 2375);
DISPLAY 1.021277 (-2450 2375);
DISPLAY INVISIBLE (-2450 2375);
FORCEADD TAP..1
(-3275 3975);
FORCEPROP 3 LASTPIN (-3325 3975) SIG_NAME M_B_CPU0_SB_DQ<2>
J 0
(-3315 3985);
DISPLAY 0.659574 (-3315 3985);
PAINT MONO (-3315 3985);
DISPLAY INVISIBLE (-3315 3985);
FORCEPROP 1 LASTPIN (-3325 3975) BN 2
J 0
(-3337 3983);
DISPLAY 0.489362 (-3337 3983);
PAINT GREEN (-3337 3983);
FORCEPROP 2 LAST CDS_LIB mstr_standard
J 0
(-3275 3975);
DISPLAY 0.723404 (-3275 3975);
PAINT MONO (-3275 3975);
DISPLAY INVISIBLE (-3275 3975);
FORCEPROP 1 LAST BODY_TYPE PLUMBING
J 0
(-3275 4025);
DISPLAY 0.872340 (-3275 4025);
PAINT GREEN (-3275 4025);
DISPLAY INVISIBLE (-3275 4025);
FORCEPROP 1 LAST HDL_TAP TRUE
J 0
(-2950 3850);
DISPLAY 0.872340 (-2950 3850);
DISPLAY INVISIBLE (-2950 3850);
FORCEPROP 1 LAST PATH I207
J 0
(-3277 3975);
DISPLAY 0.872340 (-3277 3975);
PAINT GREEN (-3277 3975);
DISPLAY INVISIBLE (-3277 3975);
FORCEADD TAP..1
(-3275 4025);
FORCEPROP 3 LASTPIN (-3325 4025) SIG_NAME M_B_CPU0_SB_DQ<1>
J 0
(-3315 4035);
DISPLAY 0.659574 (-3315 4035);
PAINT MONO (-3315 4035);
DISPLAY INVISIBLE (-3315 4035);
FORCEPROP 1 LASTPIN (-3325 4025) BN 1
J 0
(-3337 4033);
DISPLAY 0.489362 (-3337 4033);
PAINT GREEN (-3337 4033);
FORCEPROP 2 LAST CDS_LIB mstr_standard
J 0
(-3275 4025);
DISPLAY 0.723404 (-3275 4025);
PAINT MONO (-3275 4025);
DISPLAY INVISIBLE (-3275 4025);
FORCEPROP 1 LAST BODY_TYPE PLUMBING
J 0
(-3275 4075);
DISPLAY 0.872340 (-3275 4075);
PAINT GREEN (-3275 4075);
DISPLAY INVISIBLE (-3275 4075);
FORCEPROP 1 LAST HDL_TAP TRUE
J 0
(-2950 3900);
DISPLAY 0.872340 (-2950 3900);
DISPLAY INVISIBLE (-2950 3900);
FORCEPROP 1 LAST PATH I208
J 0
(-3277 4025);
DISPLAY 0.872340 (-3277 4025);
PAINT GREEN (-3277 4025);
DISPLAY INVISIBLE (-3277 4025);
FORCEADD TAP..1
(-3275 4075);
FORCEPROP 3 LASTPIN (-3325 4075) SIG_NAME M_B_CPU0_SB_DQ<0>
J 0
(-3315 4085);
DISPLAY 0.659574 (-3315 4085);
PAINT MONO (-3315 4085);
DISPLAY INVISIBLE (-3315 4085);
FORCEPROP 1 LASTPIN (-3325 4075) BN 0
J 0
(-3337 4083);
DISPLAY 0.489362 (-3337 4083);
PAINT GREEN (-3337 4083);
FORCEPROP 2 LAST CDS_LIB mstr_standard
J 0
(-3275 4075);
DISPLAY 0.723404 (-3275 4075);
PAINT MONO (-3275 4075);
DISPLAY INVISIBLE (-3275 4075);
FORCEPROP 1 LAST BODY_TYPE PLUMBING
J 0
(-3275 4125);
DISPLAY 0.872340 (-3275 4125);
PAINT GREEN (-3275 4125);
DISPLAY INVISIBLE (-3275 4125);
FORCEPROP 1 LAST HDL_TAP TRUE
J 0
(-2950 3950);
DISPLAY 0.872340 (-2950 3950);
DISPLAY INVISIBLE (-2950 3950);
FORCEPROP 1 LAST PATH I209
J 0
(-3277 4075);
DISPLAY 0.872340 (-3277 4075);
PAINT GREEN (-3277 4075);
DISPLAY INVISIBLE (-3277 4075);
FORCEADD TAP..1
(-3275 3925);
FORCEPROP 3 LASTPIN (-3325 3925) SIG_NAME M_B_CPU0_SB_DQ<3>
J 0
(-3315 3935);
DISPLAY 0.659574 (-3315 3935);
PAINT MONO (-3315 3935);
DISPLAY INVISIBLE (-3315 3935);
FORCEPROP 1 LASTPIN (-3325 3925) BN 3
J 0
(-3337 3933);
DISPLAY 0.489362 (-3337 3933);
PAINT GREEN (-3337 3933);
FORCEPROP 2 LAST CDS_LIB mstr_standard
J 0
(-3275 3925);
DISPLAY 0.723404 (-3275 3925);
PAINT MONO (-3275 3925);
DISPLAY INVISIBLE (-3275 3925);
FORCEPROP 1 LAST BODY_TYPE PLUMBING
J 0
(-3275 3975);
DISPLAY 0.872340 (-3275 3975);
PAINT GREEN (-3275 3975);
DISPLAY INVISIBLE (-3275 3975);
FORCEPROP 1 LAST HDL_TAP TRUE
J 0
(-2950 3800);
DISPLAY 0.872340 (-2950 3800);
DISPLAY INVISIBLE (-2950 3800);
FORCEPROP 1 LAST PATH I210
J 0
(-3277 3925);
DISPLAY 0.872340 (-3277 3925);
PAINT GREEN (-3277 3925);
DISPLAY INVISIBLE (-3277 3925);
FORCEADD TAP..1
(-3275 3875);
FORCEPROP 3 LASTPIN (-3325 3875) SIG_NAME M_B_CPU0_SB_DQ<4>
J 0
(-3315 3885);
DISPLAY 0.659574 (-3315 3885);
PAINT MONO (-3315 3885);
DISPLAY INVISIBLE (-3315 3885);
FORCEPROP 1 LASTPIN (-3325 3875) BN 4
J 0
(-3337 3883);
DISPLAY 0.489362 (-3337 3883);
PAINT GREEN (-3337 3883);
FORCEPROP 2 LAST CDS_LIB mstr_standard
J 0
(-3275 3875);
DISPLAY 0.723404 (-3275 3875);
PAINT MONO (-3275 3875);
DISPLAY INVISIBLE (-3275 3875);
FORCEPROP 1 LAST BODY_TYPE PLUMBING
J 0
(-3275 3925);
DISPLAY 0.872340 (-3275 3925);
PAINT GREEN (-3275 3925);
DISPLAY INVISIBLE (-3275 3925);
FORCEPROP 1 LAST HDL_TAP TRUE
J 0
(-2950 3750);
DISPLAY 0.872340 (-2950 3750);
DISPLAY INVISIBLE (-2950 3750);
FORCEPROP 1 LAST PATH I211
J 0
(-3277 3875);
DISPLAY 0.872340 (-3277 3875);
PAINT GREEN (-3277 3875);
DISPLAY INVISIBLE (-3277 3875);
FORCEADD TAP..1
(-3275 3825);
FORCEPROP 3 LASTPIN (-3325 3825) SIG_NAME M_B_CPU0_SB_DQ<5>
J 0
(-3315 3835);
DISPLAY 0.659574 (-3315 3835);
PAINT MONO (-3315 3835);
DISPLAY INVISIBLE (-3315 3835);
FORCEPROP 1 LASTPIN (-3325 3825) BN 5
J 0
(-3337 3833);
DISPLAY 0.489362 (-3337 3833);
PAINT GREEN (-3337 3833);
FORCEPROP 2 LAST CDS_LIB mstr_standard
J 0
(-3275 3825);
DISPLAY 0.723404 (-3275 3825);
PAINT MONO (-3275 3825);
DISPLAY INVISIBLE (-3275 3825);
FORCEPROP 1 LAST BODY_TYPE PLUMBING
J 0
(-3275 3875);
DISPLAY 0.872340 (-3275 3875);
PAINT GREEN (-3275 3875);
DISPLAY INVISIBLE (-3275 3875);
FORCEPROP 1 LAST HDL_TAP TRUE
J 0
(-2950 3700);
DISPLAY 0.872340 (-2950 3700);
DISPLAY INVISIBLE (-2950 3700);
FORCEPROP 1 LAST PATH I212
J 0
(-3277 3825);
DISPLAY 0.872340 (-3277 3825);
PAINT GREEN (-3277 3825);
DISPLAY INVISIBLE (-3277 3825);
FORCEADD TAP..1
(-3275 3725);
FORCEPROP 3 LASTPIN (-3325 3725) SIG_NAME M_B_CPU0_SB_DQ<7>
J 0
(-3315 3735);
DISPLAY 0.659574 (-3315 3735);
PAINT MONO (-3315 3735);
DISPLAY INVISIBLE (-3315 3735);
FORCEPROP 1 LASTPIN (-3325 3725) BN 7
J 0
(-3337 3733);
DISPLAY 0.489362 (-3337 3733);
PAINT GREEN (-3337 3733);
FORCEPROP 2 LAST CDS_LIB mstr_standard
J 0
(-3275 3725);
DISPLAY 0.723404 (-3275 3725);
PAINT MONO (-3275 3725);
DISPLAY INVISIBLE (-3275 3725);
FORCEPROP 1 LAST BODY_TYPE PLUMBING
J 0
(-3275 3775);
DISPLAY 0.872340 (-3275 3775);
PAINT GREEN (-3275 3775);
DISPLAY INVISIBLE (-3275 3775);
FORCEPROP 1 LAST HDL_TAP TRUE
J 0
(-2950 3600);
DISPLAY 0.872340 (-2950 3600);
DISPLAY INVISIBLE (-2950 3600);
FORCEPROP 1 LAST PATH I213
J 0
(-3277 3725);
DISPLAY 0.872340 (-3277 3725);
PAINT GREEN (-3277 3725);
DISPLAY INVISIBLE (-3277 3725);
FORCEADD TAP..1
(-3275 3775);
FORCEPROP 3 LASTPIN (-3325 3775) SIG_NAME M_B_CPU0_SB_DQ<6>
J 0
(-3315 3785);
DISPLAY 0.659574 (-3315 3785);
PAINT MONO (-3315 3785);
DISPLAY INVISIBLE (-3315 3785);
FORCEPROP 1 LASTPIN (-3325 3775) BN 6
J 0
(-3337 3783);
DISPLAY 0.489362 (-3337 3783);
PAINT GREEN (-3337 3783);
FORCEPROP 2 LAST CDS_LIB mstr_standard
J 0
(-3275 3775);
DISPLAY 0.723404 (-3275 3775);
PAINT MONO (-3275 3775);
DISPLAY INVISIBLE (-3275 3775);
FORCEPROP 1 LAST BODY_TYPE PLUMBING
J 0
(-3275 3825);
DISPLAY 0.872340 (-3275 3825);
PAINT GREEN (-3275 3825);
DISPLAY INVISIBLE (-3275 3825);
FORCEPROP 1 LAST HDL_TAP TRUE
J 0
(-2950 3650);
DISPLAY 0.872340 (-2950 3650);
DISPLAY INVISIBLE (-2950 3650);
FORCEPROP 1 LAST PATH I214
J 0
(-3277 3775);
DISPLAY 0.872340 (-3277 3775);
PAINT GREEN (-3277 3775);
DISPLAY INVISIBLE (-3277 3775);
FORCEADD TAP..1
(-3275 3625);
FORCEPROP 3 LASTPIN (-3325 3625) SIG_NAME M_B_CPU0_SB_DQ<8>
J 0
(-3315 3635);
DISPLAY 0.659574 (-3315 3635);
PAINT MONO (-3315 3635);
DISPLAY INVISIBLE (-3315 3635);
FORCEPROP 1 LASTPIN (-3325 3625) BN 8
J 0
(-3337 3633);
DISPLAY 0.489362 (-3337 3633);
PAINT GREEN (-3337 3633);
FORCEPROP 2 LAST CDS_LIB mstr_standard
J 0
(-3275 3625);
DISPLAY 0.723404 (-3275 3625);
PAINT MONO (-3275 3625);
DISPLAY INVISIBLE (-3275 3625);
FORCEPROP 1 LAST BODY_TYPE PLUMBING
J 0
(-3275 3675);
DISPLAY 0.872340 (-3275 3675);
PAINT GREEN (-3275 3675);
DISPLAY INVISIBLE (-3275 3675);
FORCEPROP 1 LAST HDL_TAP TRUE
J 0
(-2950 3500);
DISPLAY 0.872340 (-2950 3500);
DISPLAY INVISIBLE (-2950 3500);
FORCEPROP 1 LAST PATH I215
J 0
(-3277 3625);
DISPLAY 0.872340 (-3277 3625);
PAINT GREEN (-3277 3625);
DISPLAY INVISIBLE (-3277 3625);
FORCEADD TAP..1
(-3275 3475);
FORCEPROP 3 LASTPIN (-3325 3475) SIG_NAME M_B_CPU0_SB_DQ<11>
J 0
(-3315 3485);
DISPLAY 0.659574 (-3315 3485);
PAINT MONO (-3315 3485);
DISPLAY INVISIBLE (-3315 3485);
FORCEPROP 1 LASTPIN (-3325 3475) BN 11
J 0
(-3337 3483);
DISPLAY 0.489362 (-3337 3483);
PAINT GREEN (-3337 3483);
FORCEPROP 2 LAST CDS_LIB mstr_standard
J 0
(-3275 3475);
DISPLAY 0.723404 (-3275 3475);
PAINT MONO (-3275 3475);
DISPLAY INVISIBLE (-3275 3475);
FORCEPROP 1 LAST BODY_TYPE PLUMBING
J 0
(-3275 3525);
DISPLAY 0.872340 (-3275 3525);
PAINT GREEN (-3275 3525);
DISPLAY INVISIBLE (-3275 3525);
FORCEPROP 1 LAST HDL_TAP TRUE
J 0
(-2950 3350);
DISPLAY 0.872340 (-2950 3350);
DISPLAY INVISIBLE (-2950 3350);
FORCEPROP 1 LAST PATH I216
J 0
(-3277 3475);
DISPLAY 0.872340 (-3277 3475);
PAINT GREEN (-3277 3475);
DISPLAY INVISIBLE (-3277 3475);
FORCEADD TAP..1
(-3275 3575);
FORCEPROP 3 LASTPIN (-3325 3575) SIG_NAME M_B_CPU0_SB_DQ<9>
J 0
(-3315 3585);
DISPLAY 0.659574 (-3315 3585);
PAINT MONO (-3315 3585);
DISPLAY INVISIBLE (-3315 3585);
FORCEPROP 1 LASTPIN (-3325 3575) BN 9
J 0
(-3337 3583);
DISPLAY 0.489362 (-3337 3583);
PAINT GREEN (-3337 3583);
FORCEPROP 2 LAST CDS_LIB mstr_standard
J 0
(-3275 3575);
DISPLAY 0.723404 (-3275 3575);
PAINT MONO (-3275 3575);
DISPLAY INVISIBLE (-3275 3575);
FORCEPROP 1 LAST BODY_TYPE PLUMBING
J 0
(-3275 3625);
DISPLAY 0.872340 (-3275 3625);
PAINT GREEN (-3275 3625);
DISPLAY INVISIBLE (-3275 3625);
FORCEPROP 1 LAST HDL_TAP TRUE
J 0
(-2950 3450);
DISPLAY 0.872340 (-2950 3450);
DISPLAY INVISIBLE (-2950 3450);
FORCEPROP 1 LAST PATH I217
J 0
(-3277 3575);
DISPLAY 0.872340 (-3277 3575);
PAINT GREEN (-3277 3575);
DISPLAY INVISIBLE (-3277 3575);
FORCEADD TAP..1
(-3275 3525);
FORCEPROP 3 LASTPIN (-3325 3525) SIG_NAME M_B_CPU0_SB_DQ<10>
J 0
(-3315 3535);
DISPLAY 0.659574 (-3315 3535);
PAINT MONO (-3315 3535);
DISPLAY INVISIBLE (-3315 3535);
FORCEPROP 1 LASTPIN (-3325 3525) BN 10
J 0
(-3337 3533);
DISPLAY 0.489362 (-3337 3533);
PAINT GREEN (-3337 3533);
FORCEPROP 2 LAST CDS_LIB mstr_standard
J 0
(-3275 3525);
DISPLAY 0.723404 (-3275 3525);
PAINT MONO (-3275 3525);
DISPLAY INVISIBLE (-3275 3525);
FORCEPROP 1 LAST BODY_TYPE PLUMBING
J 0
(-3275 3575);
DISPLAY 0.872340 (-3275 3575);
PAINT GREEN (-3275 3575);
DISPLAY INVISIBLE (-3275 3575);
FORCEPROP 1 LAST HDL_TAP TRUE
J 0
(-2950 3400);
DISPLAY 0.872340 (-2950 3400);
DISPLAY INVISIBLE (-2950 3400);
FORCEPROP 1 LAST PATH I218
J 0
(-3277 3525);
DISPLAY 0.872340 (-3277 3525);
PAINT GREEN (-3277 3525);
DISPLAY INVISIBLE (-3277 3525);
FORCEADD TAP..1
(-3275 3425);
FORCEPROP 3 LASTPIN (-3325 3425) SIG_NAME M_B_CPU0_SB_DQ<12>
J 0
(-3315 3435);
DISPLAY 0.659574 (-3315 3435);
PAINT MONO (-3315 3435);
DISPLAY INVISIBLE (-3315 3435);
FORCEPROP 1 LASTPIN (-3325 3425) BN 12
J 0
(-3337 3433);
DISPLAY 0.489362 (-3337 3433);
PAINT GREEN (-3337 3433);
FORCEPROP 2 LAST CDS_LIB mstr_standard
J 0
(-3275 3425);
DISPLAY 0.723404 (-3275 3425);
PAINT MONO (-3275 3425);
DISPLAY INVISIBLE (-3275 3425);
FORCEPROP 1 LAST BODY_TYPE PLUMBING
J 0
(-3275 3475);
DISPLAY 0.872340 (-3275 3475);
PAINT GREEN (-3275 3475);
DISPLAY INVISIBLE (-3275 3475);
FORCEPROP 1 LAST HDL_TAP TRUE
J 0
(-2950 3300);
DISPLAY 0.872340 (-2950 3300);
DISPLAY INVISIBLE (-2950 3300);
FORCEPROP 1 LAST PATH I219
J 0
(-3277 3425);
DISPLAY 0.872340 (-3277 3425);
PAINT GREEN (-3277 3425);
DISPLAY INVISIBLE (-3277 3425);
FORCEADD TAP..1
(-3275 3375);
FORCEPROP 3 LASTPIN (-3325 3375) SIG_NAME M_B_CPU0_SB_DQ<13>
J 0
(-3315 3385);
DISPLAY 0.659574 (-3315 3385);
PAINT MONO (-3315 3385);
DISPLAY INVISIBLE (-3315 3385);
FORCEPROP 1 LASTPIN (-3325 3375) BN 13
J 0
(-3337 3383);
DISPLAY 0.489362 (-3337 3383);
PAINT GREEN (-3337 3383);
FORCEPROP 2 LAST CDS_LIB mstr_standard
J 0
(-3275 3375);
DISPLAY 0.723404 (-3275 3375);
PAINT MONO (-3275 3375);
DISPLAY INVISIBLE (-3275 3375);
FORCEPROP 1 LAST BODY_TYPE PLUMBING
J 0
(-3275 3425);
DISPLAY 0.872340 (-3275 3425);
PAINT GREEN (-3275 3425);
DISPLAY INVISIBLE (-3275 3425);
FORCEPROP 1 LAST HDL_TAP TRUE
J 0
(-2950 3250);
DISPLAY 0.872340 (-2950 3250);
DISPLAY INVISIBLE (-2950 3250);
FORCEPROP 1 LAST PATH I220
J 0
(-3277 3375);
DISPLAY 0.872340 (-3277 3375);
PAINT GREEN (-3277 3375);
DISPLAY INVISIBLE (-3277 3375);
FORCEADD TAP..1
(-3275 3275);
FORCEPROP 3 LASTPIN (-3325 3275) SIG_NAME M_B_CPU0_SB_DQ<15>
J 0
(-3315 3285);
DISPLAY 0.659574 (-3315 3285);
PAINT MONO (-3315 3285);
DISPLAY INVISIBLE (-3315 3285);
FORCEPROP 1 LASTPIN (-3325 3275) BN 15
J 0
(-3337 3283);
DISPLAY 0.489362 (-3337 3283);
PAINT GREEN (-3337 3283);
FORCEPROP 2 LAST CDS_LIB mstr_standard
J 0
(-3275 3275);
DISPLAY 0.723404 (-3275 3275);
PAINT MONO (-3275 3275);
DISPLAY INVISIBLE (-3275 3275);
FORCEPROP 1 LAST BODY_TYPE PLUMBING
J 0
(-3275 3325);
DISPLAY 0.872340 (-3275 3325);
PAINT GREEN (-3275 3325);
DISPLAY INVISIBLE (-3275 3325);
FORCEPROP 1 LAST HDL_TAP TRUE
J 0
(-2950 3150);
DISPLAY 0.872340 (-2950 3150);
DISPLAY INVISIBLE (-2950 3150);
FORCEPROP 1 LAST PATH I221
J 0
(-3277 3275);
DISPLAY 0.872340 (-3277 3275);
PAINT GREEN (-3277 3275);
DISPLAY INVISIBLE (-3277 3275);
FORCEADD TAP..1
(-3275 3325);
FORCEPROP 3 LASTPIN (-3325 3325) SIG_NAME M_B_CPU0_SB_DQ<14>
J 0
(-3315 3335);
DISPLAY 0.659574 (-3315 3335);
PAINT MONO (-3315 3335);
DISPLAY INVISIBLE (-3315 3335);
FORCEPROP 1 LASTPIN (-3325 3325) BN 14
J 0
(-3337 3333);
DISPLAY 0.489362 (-3337 3333);
PAINT GREEN (-3337 3333);
FORCEPROP 2 LAST CDS_LIB mstr_standard
J 0
(-3275 3325);
DISPLAY 0.723404 (-3275 3325);
PAINT MONO (-3275 3325);
DISPLAY INVISIBLE (-3275 3325);
FORCEPROP 1 LAST BODY_TYPE PLUMBING
J 0
(-3275 3375);
DISPLAY 0.872340 (-3275 3375);
PAINT GREEN (-3275 3375);
DISPLAY INVISIBLE (-3275 3375);
FORCEPROP 1 LAST HDL_TAP TRUE
J 0
(-2950 3200);
DISPLAY 0.872340 (-2950 3200);
DISPLAY INVISIBLE (-2950 3200);
FORCEPROP 1 LAST PATH I222
J 0
(-3277 3325);
DISPLAY 0.872340 (-3277 3325);
PAINT GREEN (-3277 3325);
DISPLAY INVISIBLE (-3277 3325);
FORCEADD TAP..1
(-3275 3175);
FORCEPROP 3 LASTPIN (-3325 3175) SIG_NAME M_B_CPU0_SB_DQ<16>
J 0
(-3315 3185);
DISPLAY 0.659574 (-3315 3185);
PAINT MONO (-3315 3185);
DISPLAY INVISIBLE (-3315 3185);
FORCEPROP 1 LASTPIN (-3325 3175) BN 16
J 0
(-3337 3183);
DISPLAY 0.489362 (-3337 3183);
PAINT GREEN (-3337 3183);
FORCEPROP 2 LAST CDS_LIB mstr_standard
J 0
(-3275 3175);
DISPLAY 0.723404 (-3275 3175);
PAINT MONO (-3275 3175);
DISPLAY INVISIBLE (-3275 3175);
FORCEPROP 1 LAST BODY_TYPE PLUMBING
J 0
(-3275 3225);
DISPLAY 0.872340 (-3275 3225);
PAINT GREEN (-3275 3225);
DISPLAY INVISIBLE (-3275 3225);
FORCEPROP 1 LAST HDL_TAP TRUE
J 0
(-2950 3050);
DISPLAY 0.872340 (-2950 3050);
DISPLAY INVISIBLE (-2950 3050);
FORCEPROP 1 LAST PATH I223
J 0
(-3277 3175);
DISPLAY 0.872340 (-3277 3175);
PAINT GREEN (-3277 3175);
DISPLAY INVISIBLE (-3277 3175);
FORCEADD TAP..1
(-3275 3125);
FORCEPROP 3 LASTPIN (-3325 3125) SIG_NAME M_B_CPU0_SB_DQ<17>
J 0
(-3315 3135);
DISPLAY 0.659574 (-3315 3135);
PAINT MONO (-3315 3135);
DISPLAY INVISIBLE (-3315 3135);
FORCEPROP 1 LASTPIN (-3325 3125) BN 17
J 0
(-3337 3133);
DISPLAY 0.489362 (-3337 3133);
PAINT GREEN (-3337 3133);
FORCEPROP 2 LAST CDS_LIB mstr_standard
J 0
(-3275 3125);
DISPLAY 0.723404 (-3275 3125);
PAINT MONO (-3275 3125);
DISPLAY INVISIBLE (-3275 3125);
FORCEPROP 1 LAST BODY_TYPE PLUMBING
J 0
(-3275 3175);
DISPLAY 0.872340 (-3275 3175);
PAINT GREEN (-3275 3175);
DISPLAY INVISIBLE (-3275 3175);
FORCEPROP 1 LAST HDL_TAP TRUE
J 0
(-2950 3000);
DISPLAY 0.872340 (-2950 3000);
DISPLAY INVISIBLE (-2950 3000);
FORCEPROP 1 LAST PATH I224
J 0
(-3277 3125);
DISPLAY 0.872340 (-3277 3125);
PAINT GREEN (-3277 3125);
DISPLAY INVISIBLE (-3277 3125);
FORCEADD TAP..1
(-3275 3075);
FORCEPROP 3 LASTPIN (-3325 3075) SIG_NAME M_B_CPU0_SB_DQ<18>
J 0
(-3315 3085);
DISPLAY 0.659574 (-3315 3085);
PAINT MONO (-3315 3085);
DISPLAY INVISIBLE (-3315 3085);
FORCEPROP 1 LASTPIN (-3325 3075) BN 18
J 0
(-3337 3083);
DISPLAY 0.489362 (-3337 3083);
PAINT GREEN (-3337 3083);
FORCEPROP 2 LAST CDS_LIB mstr_standard
J 0
(-3275 3075);
DISPLAY 0.723404 (-3275 3075);
PAINT MONO (-3275 3075);
DISPLAY INVISIBLE (-3275 3075);
FORCEPROP 1 LAST BODY_TYPE PLUMBING
J 0
(-3275 3125);
DISPLAY 0.872340 (-3275 3125);
PAINT GREEN (-3275 3125);
DISPLAY INVISIBLE (-3275 3125);
FORCEPROP 1 LAST HDL_TAP TRUE
J 0
(-2950 2950);
DISPLAY 0.872340 (-2950 2950);
DISPLAY INVISIBLE (-2950 2950);
FORCEPROP 1 LAST PATH I225
J 0
(-3277 3075);
DISPLAY 0.872340 (-3277 3075);
PAINT GREEN (-3277 3075);
DISPLAY INVISIBLE (-3277 3075);
FORCEADD TAP..1
(-3275 2975);
FORCEPROP 3 LASTPIN (-3325 2975) SIG_NAME M_B_CPU0_SB_DQ<20>
J 0
(-3315 2985);
DISPLAY 0.659574 (-3315 2985);
PAINT MONO (-3315 2985);
DISPLAY INVISIBLE (-3315 2985);
FORCEPROP 1 LASTPIN (-3325 2975) BN 20
J 0
(-3337 2983);
DISPLAY 0.489362 (-3337 2983);
PAINT GREEN (-3337 2983);
FORCEPROP 2 LAST CDS_LIB mstr_standard
J 0
(-3275 2975);
DISPLAY 0.723404 (-3275 2975);
PAINT MONO (-3275 2975);
DISPLAY INVISIBLE (-3275 2975);
FORCEPROP 1 LAST BODY_TYPE PLUMBING
J 0
(-3275 3025);
DISPLAY 0.872340 (-3275 3025);
PAINT GREEN (-3275 3025);
DISPLAY INVISIBLE (-3275 3025);
FORCEPROP 1 LAST HDL_TAP TRUE
J 0
(-2950 2850);
DISPLAY 0.872340 (-2950 2850);
DISPLAY INVISIBLE (-2950 2850);
FORCEPROP 1 LAST PATH I226
J 0
(-3277 2975);
DISPLAY 0.872340 (-3277 2975);
PAINT GREEN (-3277 2975);
DISPLAY INVISIBLE (-3277 2975);
FORCEADD TAP..1
(-3275 3025);
FORCEPROP 3 LASTPIN (-3325 3025) SIG_NAME M_B_CPU0_SB_DQ<19>
J 0
(-3315 3035);
DISPLAY 0.659574 (-3315 3035);
PAINT MONO (-3315 3035);
DISPLAY INVISIBLE (-3315 3035);
FORCEPROP 1 LASTPIN (-3325 3025) BN 19
J 0
(-3337 3033);
DISPLAY 0.489362 (-3337 3033);
PAINT GREEN (-3337 3033);
FORCEPROP 2 LAST CDS_LIB mstr_standard
J 0
(-3275 3025);
DISPLAY 0.723404 (-3275 3025);
PAINT MONO (-3275 3025);
DISPLAY INVISIBLE (-3275 3025);
FORCEPROP 1 LAST BODY_TYPE PLUMBING
J 0
(-3275 3075);
DISPLAY 0.872340 (-3275 3075);
PAINT GREEN (-3275 3075);
DISPLAY INVISIBLE (-3275 3075);
FORCEPROP 1 LAST HDL_TAP TRUE
J 0
(-2950 2900);
DISPLAY 0.872340 (-2950 2900);
DISPLAY INVISIBLE (-2950 2900);
FORCEPROP 1 LAST PATH I227
J 0
(-3277 3025);
DISPLAY 0.872340 (-3277 3025);
PAINT GREEN (-3277 3025);
DISPLAY INVISIBLE (-3277 3025);
FORCEADD TAP..1
(-3275 2825);
FORCEPROP 3 LASTPIN (-3325 2825) SIG_NAME M_B_CPU0_SB_DQ<23>
J 0
(-3315 2835);
DISPLAY 0.659574 (-3315 2835);
PAINT MONO (-3315 2835);
DISPLAY INVISIBLE (-3315 2835);
FORCEPROP 1 LASTPIN (-3325 2825) BN 23
J 0
(-3337 2833);
DISPLAY 0.489362 (-3337 2833);
PAINT GREEN (-3337 2833);
FORCEPROP 2 LAST CDS_LIB mstr_standard
J 0
(-3275 2825);
DISPLAY 0.723404 (-3275 2825);
PAINT MONO (-3275 2825);
DISPLAY INVISIBLE (-3275 2825);
FORCEPROP 1 LAST BODY_TYPE PLUMBING
J 0
(-3275 2875);
DISPLAY 0.872340 (-3275 2875);
PAINT GREEN (-3275 2875);
DISPLAY INVISIBLE (-3275 2875);
FORCEPROP 1 LAST HDL_TAP TRUE
J 0
(-2950 2700);
DISPLAY 0.872340 (-2950 2700);
DISPLAY INVISIBLE (-2950 2700);
FORCEPROP 1 LAST PATH I228
J 0
(-3277 2825);
DISPLAY 0.872340 (-3277 2825);
PAINT GREEN (-3277 2825);
DISPLAY INVISIBLE (-3277 2825);
FORCEADD TAP..1
(-3275 2925);
FORCEPROP 3 LASTPIN (-3325 2925) SIG_NAME M_B_CPU0_SB_DQ<21>
J 0
(-3315 2935);
DISPLAY 0.659574 (-3315 2935);
PAINT MONO (-3315 2935);
DISPLAY INVISIBLE (-3315 2935);
FORCEPROP 1 LASTPIN (-3325 2925) BN 21
J 0
(-3337 2933);
DISPLAY 0.489362 (-3337 2933);
PAINT GREEN (-3337 2933);
FORCEPROP 2 LAST CDS_LIB mstr_standard
J 0
(-3275 2925);
DISPLAY 0.723404 (-3275 2925);
PAINT MONO (-3275 2925);
DISPLAY INVISIBLE (-3275 2925);
FORCEPROP 1 LAST BODY_TYPE PLUMBING
J 0
(-3275 2975);
DISPLAY 0.872340 (-3275 2975);
PAINT GREEN (-3275 2975);
DISPLAY INVISIBLE (-3275 2975);
FORCEPROP 1 LAST HDL_TAP TRUE
J 0
(-2950 2800);
DISPLAY 0.872340 (-2950 2800);
DISPLAY INVISIBLE (-2950 2800);
FORCEPROP 1 LAST PATH I229
J 0
(-3277 2925);
DISPLAY 0.872340 (-3277 2925);
PAINT GREEN (-3277 2925);
DISPLAY INVISIBLE (-3277 2925);
FORCEADD TAP..1
(-3275 2875);
FORCEPROP 3 LASTPIN (-3325 2875) SIG_NAME M_B_CPU0_SB_DQ<22>
J 0
(-3315 2885);
DISPLAY 0.659574 (-3315 2885);
PAINT MONO (-3315 2885);
DISPLAY INVISIBLE (-3315 2885);
FORCEPROP 1 LASTPIN (-3325 2875) BN 22
J 0
(-3337 2883);
DISPLAY 0.489362 (-3337 2883);
PAINT GREEN (-3337 2883);
FORCEPROP 2 LAST CDS_LIB mstr_standard
J 0
(-3275 2875);
DISPLAY 0.723404 (-3275 2875);
PAINT MONO (-3275 2875);
DISPLAY INVISIBLE (-3275 2875);
FORCEPROP 1 LAST BODY_TYPE PLUMBING
J 0
(-3275 2925);
DISPLAY 0.872340 (-3275 2925);
PAINT GREEN (-3275 2925);
DISPLAY INVISIBLE (-3275 2925);
FORCEPROP 1 LAST HDL_TAP TRUE
J 0
(-2950 2750);
DISPLAY 0.872340 (-2950 2750);
DISPLAY INVISIBLE (-2950 2750);
FORCEPROP 1 LAST PATH I230
J 0
(-3277 2875);
DISPLAY 0.872340 (-3277 2875);
PAINT GREEN (-3277 2875);
DISPLAY INVISIBLE (-3277 2875);
FORCEADD TAP..1
(-3275 2725);
FORCEPROP 3 LASTPIN (-3325 2725) SIG_NAME M_B_CPU0_SB_DQ<24>
J 0
(-3315 2735);
DISPLAY 0.659574 (-3315 2735);
PAINT MONO (-3315 2735);
DISPLAY INVISIBLE (-3315 2735);
FORCEPROP 1 LASTPIN (-3325 2725) BN 24
J 0
(-3337 2733);
DISPLAY 0.489362 (-3337 2733);
PAINT GREEN (-3337 2733);
FORCEPROP 2 LAST CDS_LIB mstr_standard
J 0
(-3275 2725);
DISPLAY 0.723404 (-3275 2725);
PAINT MONO (-3275 2725);
DISPLAY INVISIBLE (-3275 2725);
FORCEPROP 1 LAST BODY_TYPE PLUMBING
J 0
(-3275 2775);
DISPLAY 0.872340 (-3275 2775);
PAINT GREEN (-3275 2775);
DISPLAY INVISIBLE (-3275 2775);
FORCEPROP 1 LAST HDL_TAP TRUE
J 0
(-2950 2600);
DISPLAY 0.872340 (-2950 2600);
DISPLAY INVISIBLE (-2950 2600);
FORCEPROP 1 LAST PATH I231
J 0
(-3277 2725);
DISPLAY 0.872340 (-3277 2725);
PAINT GREEN (-3277 2725);
DISPLAY INVISIBLE (-3277 2725);
FORCEADD TAP..1
(-3275 2625);
FORCEPROP 3 LASTPIN (-3325 2625) SIG_NAME M_B_CPU0_SB_DQ<26>
J 0
(-3315 2635);
DISPLAY 0.659574 (-3315 2635);
PAINT MONO (-3315 2635);
DISPLAY INVISIBLE (-3315 2635);
FORCEPROP 1 LASTPIN (-3325 2625) BN 26
J 0
(-3337 2633);
DISPLAY 0.489362 (-3337 2633);
PAINT GREEN (-3337 2633);
FORCEPROP 2 LAST CDS_LIB mstr_standard
J 0
(-3275 2625);
DISPLAY 0.723404 (-3275 2625);
PAINT MONO (-3275 2625);
DISPLAY INVISIBLE (-3275 2625);
FORCEPROP 1 LAST BODY_TYPE PLUMBING
J 0
(-3275 2675);
DISPLAY 0.872340 (-3275 2675);
PAINT GREEN (-3275 2675);
DISPLAY INVISIBLE (-3275 2675);
FORCEPROP 1 LAST HDL_TAP TRUE
J 0
(-2950 2500);
DISPLAY 0.872340 (-2950 2500);
DISPLAY INVISIBLE (-2950 2500);
FORCEPROP 1 LAST PATH I232
J 0
(-3277 2625);
DISPLAY 0.872340 (-3277 2625);
PAINT GREEN (-3277 2625);
DISPLAY INVISIBLE (-3277 2625);
FORCEADD TAP..1
(-3275 2675);
FORCEPROP 3 LASTPIN (-3325 2675) SIG_NAME M_B_CPU0_SB_DQ<25>
J 0
(-3315 2685);
DISPLAY 0.659574 (-3315 2685);
PAINT MONO (-3315 2685);
DISPLAY INVISIBLE (-3315 2685);
FORCEPROP 1 LASTPIN (-3325 2675) BN 25
J 0
(-3337 2683);
DISPLAY 0.489362 (-3337 2683);
PAINT GREEN (-3337 2683);
FORCEPROP 2 LAST CDS_LIB mstr_standard
J 0
(-3275 2675);
DISPLAY 0.723404 (-3275 2675);
PAINT MONO (-3275 2675);
DISPLAY INVISIBLE (-3275 2675);
FORCEPROP 1 LAST BODY_TYPE PLUMBING
J 0
(-3275 2725);
DISPLAY 0.872340 (-3275 2725);
PAINT GREEN (-3275 2725);
DISPLAY INVISIBLE (-3275 2725);
FORCEPROP 1 LAST HDL_TAP TRUE
J 0
(-2950 2550);
DISPLAY 0.872340 (-2950 2550);
DISPLAY INVISIBLE (-2950 2550);
FORCEPROP 1 LAST PATH I233
J 0
(-3277 2675);
DISPLAY 0.872340 (-3277 2675);
PAINT GREEN (-3277 2675);
DISPLAY INVISIBLE (-3277 2675);
FORCEADD TAP..1
(-3275 2575);
FORCEPROP 3 LASTPIN (-3325 2575) SIG_NAME M_B_CPU0_SB_DQ<27>
J 0
(-3315 2585);
DISPLAY 0.659574 (-3315 2585);
PAINT MONO (-3315 2585);
DISPLAY INVISIBLE (-3315 2585);
FORCEPROP 1 LASTPIN (-3325 2575) BN 27
J 0
(-3337 2583);
DISPLAY 0.489362 (-3337 2583);
PAINT GREEN (-3337 2583);
FORCEPROP 2 LAST CDS_LIB mstr_standard
J 0
(-3275 2575);
DISPLAY 0.723404 (-3275 2575);
PAINT MONO (-3275 2575);
DISPLAY INVISIBLE (-3275 2575);
FORCEPROP 1 LAST BODY_TYPE PLUMBING
J 0
(-3275 2625);
DISPLAY 0.872340 (-3275 2625);
PAINT GREEN (-3275 2625);
DISPLAY INVISIBLE (-3275 2625);
FORCEPROP 1 LAST HDL_TAP TRUE
J 0
(-2950 2450);
DISPLAY 0.872340 (-2950 2450);
DISPLAY INVISIBLE (-2950 2450);
FORCEPROP 1 LAST PATH I234
J 0
(-3277 2575);
DISPLAY 0.872340 (-3277 2575);
PAINT GREEN (-3277 2575);
DISPLAY INVISIBLE (-3277 2575);
FORCEADD TAP..1
(-3275 2525);
FORCEPROP 3 LASTPIN (-3325 2525) SIG_NAME M_B_CPU0_SB_DQ<28>
J 0
(-3315 2535);
DISPLAY 0.659574 (-3315 2535);
PAINT MONO (-3315 2535);
DISPLAY INVISIBLE (-3315 2535);
FORCEPROP 1 LASTPIN (-3325 2525) BN 28
J 0
(-3337 2533);
DISPLAY 0.489362 (-3337 2533);
PAINT GREEN (-3337 2533);
FORCEPROP 2 LAST CDS_LIB mstr_standard
J 0
(-3275 2525);
DISPLAY 0.723404 (-3275 2525);
PAINT MONO (-3275 2525);
DISPLAY INVISIBLE (-3275 2525);
FORCEPROP 1 LAST BODY_TYPE PLUMBING
J 0
(-3275 2575);
DISPLAY 0.872340 (-3275 2575);
PAINT GREEN (-3275 2575);
DISPLAY INVISIBLE (-3275 2575);
FORCEPROP 1 LAST HDL_TAP TRUE
J 0
(-2950 2400);
DISPLAY 0.872340 (-2950 2400);
DISPLAY INVISIBLE (-2950 2400);
FORCEPROP 1 LAST PATH I235
J 0
(-3277 2525);
DISPLAY 0.872340 (-3277 2525);
PAINT GREEN (-3277 2525);
DISPLAY INVISIBLE (-3277 2525);
FORCEADD TAP..1
(-3275 2475);
FORCEPROP 3 LASTPIN (-3325 2475) SIG_NAME M_B_CPU0_SB_DQ<29>
J 0
(-3315 2485);
DISPLAY 0.659574 (-3315 2485);
PAINT MONO (-3315 2485);
DISPLAY INVISIBLE (-3315 2485);
FORCEPROP 1 LASTPIN (-3325 2475) BN 29
J 0
(-3337 2483);
DISPLAY 0.489362 (-3337 2483);
PAINT GREEN (-3337 2483);
FORCEPROP 2 LAST CDS_LIB mstr_standard
J 0
(-3275 2475);
DISPLAY 0.723404 (-3275 2475);
PAINT MONO (-3275 2475);
DISPLAY INVISIBLE (-3275 2475);
FORCEPROP 1 LAST BODY_TYPE PLUMBING
J 0
(-3275 2525);
DISPLAY 0.872340 (-3275 2525);
PAINT GREEN (-3275 2525);
DISPLAY INVISIBLE (-3275 2525);
FORCEPROP 1 LAST HDL_TAP TRUE
J 0
(-2950 2350);
DISPLAY 0.872340 (-2950 2350);
DISPLAY INVISIBLE (-2950 2350);
FORCEPROP 1 LAST PATH I236
J 0
(-3277 2475);
DISPLAY 0.872340 (-3277 2475);
PAINT GREEN (-3277 2475);
DISPLAY INVISIBLE (-3277 2475);
FORCEADD TAP..1
(-3275 2425);
FORCEPROP 3 LASTPIN (-3325 2425) SIG_NAME M_B_CPU0_SB_DQ<30>
J 0
(-3315 2435);
DISPLAY 0.659574 (-3315 2435);
PAINT MONO (-3315 2435);
DISPLAY INVISIBLE (-3315 2435);
FORCEPROP 1 LASTPIN (-3325 2425) BN 30
J 0
(-3337 2433);
DISPLAY 0.489362 (-3337 2433);
PAINT GREEN (-3337 2433);
FORCEPROP 2 LAST CDS_LIB mstr_standard
J 0
(-3275 2425);
DISPLAY 0.723404 (-3275 2425);
PAINT MONO (-3275 2425);
DISPLAY INVISIBLE (-3275 2425);
FORCEPROP 1 LAST BODY_TYPE PLUMBING
J 0
(-3275 2475);
DISPLAY 0.872340 (-3275 2475);
PAINT GREEN (-3275 2475);
DISPLAY INVISIBLE (-3275 2475);
FORCEPROP 1 LAST HDL_TAP TRUE
J 0
(-2950 2300);
DISPLAY 0.872340 (-2950 2300);
DISPLAY INVISIBLE (-2950 2300);
FORCEPROP 1 LAST PATH I237
J 0
(-3277 2425);
DISPLAY 0.872340 (-3277 2425);
PAINT GREEN (-3277 2425);
DISPLAY INVISIBLE (-3277 2425);
FORCEADD TAP..1
(-3275 2375);
FORCEPROP 3 LASTPIN (-3325 2375) SIG_NAME M_B_CPU0_SB_DQ<31>
J 0
(-3315 2385);
DISPLAY 0.659574 (-3315 2385);
PAINT MONO (-3315 2385);
DISPLAY INVISIBLE (-3315 2385);
FORCEPROP 1 LASTPIN (-3325 2375) BN 31
J 0
(-3337 2383);
DISPLAY 0.489362 (-3337 2383);
PAINT GREEN (-3337 2383);
FORCEPROP 2 LAST CDS_LIB mstr_standard
J 0
(-3275 2375);
DISPLAY 0.723404 (-3275 2375);
PAINT MONO (-3275 2375);
DISPLAY INVISIBLE (-3275 2375);
FORCEPROP 1 LAST BODY_TYPE PLUMBING
J 0
(-3275 2425);
DISPLAY 0.872340 (-3275 2425);
PAINT GREEN (-3275 2425);
DISPLAY INVISIBLE (-3275 2425);
FORCEPROP 1 LAST HDL_TAP TRUE
J 0
(-2950 2250);
DISPLAY 0.872340 (-2950 2250);
DISPLAY INVISIBLE (-2950 2250);
FORCEPROP 1 LAST PATH I238
J 0
(-3277 2375);
DISPLAY 0.872340 (-3277 2375);
PAINT GREEN (-3277 2375);
DISPLAY INVISIBLE (-3277 2375);
FORCEADD TAP..1
(-3275 2275);
FORCEPROP 3 LASTPIN (-3325 2275) SIG_NAME M_B_CPU0_SA_CB<0>
J 0
(-3315 2285);
DISPLAY 0.659574 (-3315 2285);
PAINT MONO (-3315 2285);
DISPLAY INVISIBLE (-3315 2285);
FORCEPROP 1 LASTPIN (-3325 2275) BN 0
J 0
(-3337 2283);
DISPLAY 0.489362 (-3337 2283);
PAINT GREEN (-3337 2283);
FORCEPROP 2 LAST CDS_LIB mstr_standard
J 2
(-3275 2275);
DISPLAY 0.723404 (-3275 2275);
PAINT MONO (-3275 2275);
DISPLAY INVISIBLE (-3275 2275);
FORCEPROP 1 LAST BODY_TYPE PLUMBING
J 0
(-3275 2325);
DISPLAY 0.872340 (-3275 2325);
PAINT GREEN (-3275 2325);
DISPLAY INVISIBLE (-3275 2325);
FORCEPROP 1 LAST HDL_TAP TRUE
J 0
(-2950 2150);
DISPLAY 0.872340 (-2950 2150);
DISPLAY INVISIBLE (-2950 2150);
FORCEPROP 1 LAST PATH I239
J 0
(-3277 2275);
DISPLAY 0.872340 (-3277 2275);
PAINT GREEN (-3277 2275);
DISPLAY INVISIBLE (-3277 2275);
FORCEADD TAP..1
(-3275 2225);
FORCEPROP 3 LASTPIN (-3325 2225) SIG_NAME M_B_CPU0_SA_CB<1>
J 0
(-3315 2235);
DISPLAY 0.659574 (-3315 2235);
PAINT MONO (-3315 2235);
DISPLAY INVISIBLE (-3315 2235);
FORCEPROP 1 LASTPIN (-3325 2225) BN 1
J 0
(-3337 2233);
DISPLAY 0.489362 (-3337 2233);
PAINT GREEN (-3337 2233);
FORCEPROP 2 LAST CDS_LIB mstr_standard
J 2
(-3275 2225);
DISPLAY 0.723404 (-3275 2225);
PAINT MONO (-3275 2225);
DISPLAY INVISIBLE (-3275 2225);
FORCEPROP 1 LAST BODY_TYPE PLUMBING
J 0
(-3275 2275);
DISPLAY 0.872340 (-3275 2275);
PAINT GREEN (-3275 2275);
DISPLAY INVISIBLE (-3275 2275);
FORCEPROP 1 LAST HDL_TAP TRUE
J 0
(-2950 2100);
DISPLAY 0.872340 (-2950 2100);
DISPLAY INVISIBLE (-2950 2100);
FORCEPROP 1 LAST PATH I240
J 0
(-3277 2225);
DISPLAY 0.872340 (-3277 2225);
PAINT GREEN (-3277 2225);
DISPLAY INVISIBLE (-3277 2225);
FORCEADD TAP..1
(-3275 2075);
FORCEPROP 3 LASTPIN (-3325 2075) SIG_NAME M_B_CPU0_SA_CB<4>
J 0
(-3315 2085);
DISPLAY 0.659574 (-3315 2085);
PAINT MONO (-3315 2085);
DISPLAY INVISIBLE (-3315 2085);
FORCEPROP 1 LASTPIN (-3325 2075) BN 4
J 0
(-3337 2083);
DISPLAY 0.489362 (-3337 2083);
PAINT GREEN (-3337 2083);
FORCEPROP 2 LAST CDS_LIB mstr_standard
J 2
(-3275 2075);
DISPLAY 0.723404 (-3275 2075);
PAINT MONO (-3275 2075);
DISPLAY INVISIBLE (-3275 2075);
FORCEPROP 1 LAST BODY_TYPE PLUMBING
J 0
(-3275 2125);
DISPLAY 0.872340 (-3275 2125);
PAINT GREEN (-3275 2125);
DISPLAY INVISIBLE (-3275 2125);
FORCEPROP 1 LAST HDL_TAP TRUE
J 0
(-2950 1950);
DISPLAY 0.872340 (-2950 1950);
DISPLAY INVISIBLE (-2950 1950);
FORCEPROP 1 LAST PATH I241
J 0
(-3277 2075);
DISPLAY 0.872340 (-3277 2075);
PAINT GREEN (-3277 2075);
DISPLAY INVISIBLE (-3277 2075);
FORCEADD TAP..1
(-3275 2175);
FORCEPROP 3 LASTPIN (-3325 2175) SIG_NAME M_B_CPU0_SA_CB<2>
J 0
(-3315 2185);
DISPLAY 0.659574 (-3315 2185);
PAINT MONO (-3315 2185);
DISPLAY INVISIBLE (-3315 2185);
FORCEPROP 1 LASTPIN (-3325 2175) BN 2
J 0
(-3337 2183);
DISPLAY 0.489362 (-3337 2183);
PAINT GREEN (-3337 2183);
FORCEPROP 2 LAST CDS_LIB mstr_standard
J 2
(-3275 2175);
DISPLAY 0.723404 (-3275 2175);
PAINT MONO (-3275 2175);
DISPLAY INVISIBLE (-3275 2175);
FORCEPROP 1 LAST BODY_TYPE PLUMBING
J 0
(-3275 2225);
DISPLAY 0.872340 (-3275 2225);
PAINT GREEN (-3275 2225);
DISPLAY INVISIBLE (-3275 2225);
FORCEPROP 1 LAST HDL_TAP TRUE
J 0
(-2950 2050);
DISPLAY 0.872340 (-2950 2050);
DISPLAY INVISIBLE (-2950 2050);
FORCEPROP 1 LAST PATH I242
J 0
(-3277 2175);
DISPLAY 0.872340 (-3277 2175);
PAINT GREEN (-3277 2175);
DISPLAY INVISIBLE (-3277 2175);
FORCEADD TAP..1
(-3275 2125);
FORCEPROP 3 LASTPIN (-3325 2125) SIG_NAME M_B_CPU0_SA_CB<3>
J 0
(-3315 2135);
DISPLAY 0.659574 (-3315 2135);
PAINT MONO (-3315 2135);
DISPLAY INVISIBLE (-3315 2135);
FORCEPROP 1 LASTPIN (-3325 2125) BN 3
J 0
(-3337 2133);
DISPLAY 0.489362 (-3337 2133);
PAINT GREEN (-3337 2133);
FORCEPROP 2 LAST CDS_LIB mstr_standard
J 2
(-3275 2125);
DISPLAY 0.723404 (-3275 2125);
PAINT MONO (-3275 2125);
DISPLAY INVISIBLE (-3275 2125);
FORCEPROP 1 LAST BODY_TYPE PLUMBING
J 0
(-3275 2175);
DISPLAY 0.872340 (-3275 2175);
PAINT GREEN (-3275 2175);
DISPLAY INVISIBLE (-3275 2175);
FORCEPROP 1 LAST HDL_TAP TRUE
J 0
(-2950 2000);
DISPLAY 0.872340 (-2950 2000);
DISPLAY INVISIBLE (-2950 2000);
FORCEPROP 1 LAST PATH I243
J 0
(-3277 2125);
DISPLAY 0.872340 (-3277 2125);
PAINT GREEN (-3277 2125);
DISPLAY INVISIBLE (-3277 2125);
FORCEADD OFFPAGE..6
R 2
(-2675 1875);
FORCEPROP 2 LAST $XR0 87 
J 0
(-2461 1875);
DISPLAY 0.638298 (-2461 1875);
PAINT MONO (-2461 1875);
FORCEPROP 2 LAST CDS_LIB mstr_standard
J 2
(-2675 1875);
DISPLAY 0.723404 (-2675 1875);
PAINT MONO (-2675 1875);
DISPLAY INVISIBLE (-2675 1875);
FORCEPROP 1 LAST OFFPAGE TRUE
J 2
(-3000 1750);
DISPLAY 0.872340 (-3000 1750);
PAINT GREEN (-3000 1750);
DISPLAY INVISIBLE (-3000 1750);
FORCEPROP 1 LAST COMMENT_BODY TRUE
J 2
(-2775 1800);
DISPLAY 0.872340 (-2775 1800);
PAINT GREEN (-2775 1800);
DISPLAY INVISIBLE (-2775 1800);
FORCEPROP 2 LAST PATH I244
J 0
(-2450 1925);
DISPLAY 1.021277 (-2450 1925);
DISPLAY INVISIBLE (-2450 1925);
FORCEADD TAP..1
(-3275 1925);
FORCEPROP 3 LASTPIN (-3325 1925) SIG_NAME M_B_CPU0_SA_CB<7>
J 0
(-3315 1935);
DISPLAY 0.659574 (-3315 1935);
PAINT MONO (-3315 1935);
DISPLAY INVISIBLE (-3315 1935);
FORCEPROP 1 LASTPIN (-3325 1925) BN 7
J 0
(-3337 1933);
DISPLAY 0.489362 (-3337 1933);
PAINT GREEN (-3337 1933);
FORCEPROP 2 LAST CDS_LIB mstr_standard
J 2
(-3275 1925);
DISPLAY 0.723404 (-3275 1925);
PAINT MONO (-3275 1925);
DISPLAY INVISIBLE (-3275 1925);
FORCEPROP 1 LAST BODY_TYPE PLUMBING
J 0
(-3275 1975);
DISPLAY 0.872340 (-3275 1975);
PAINT GREEN (-3275 1975);
DISPLAY INVISIBLE (-3275 1975);
FORCEPROP 1 LAST HDL_TAP TRUE
J 0
(-2950 1800);
DISPLAY 0.872340 (-2950 1800);
DISPLAY INVISIBLE (-2950 1800);
FORCEPROP 1 LAST PATH I245
J 0
(-3277 1925);
DISPLAY 0.872340 (-3277 1925);
PAINT GREEN (-3277 1925);
DISPLAY INVISIBLE (-3277 1925);
FORCEADD TAP..1
(-3275 2025);
FORCEPROP 3 LASTPIN (-3325 2025) SIG_NAME M_B_CPU0_SA_CB<5>
J 0
(-3315 2035);
DISPLAY 0.659574 (-3315 2035);
PAINT MONO (-3315 2035);
DISPLAY INVISIBLE (-3315 2035);
FORCEPROP 1 LASTPIN (-3325 2025) BN 5
J 0
(-3337 2033);
DISPLAY 0.489362 (-3337 2033);
PAINT GREEN (-3337 2033);
FORCEPROP 2 LAST CDS_LIB mstr_standard
J 2
(-3275 2025);
DISPLAY 0.723404 (-3275 2025);
PAINT MONO (-3275 2025);
DISPLAY INVISIBLE (-3275 2025);
FORCEPROP 1 LAST BODY_TYPE PLUMBING
J 0
(-3275 2075);
DISPLAY 0.872340 (-3275 2075);
PAINT GREEN (-3275 2075);
DISPLAY INVISIBLE (-3275 2075);
FORCEPROP 1 LAST HDL_TAP TRUE
J 0
(-2950 1900);
DISPLAY 0.872340 (-2950 1900);
DISPLAY INVISIBLE (-2950 1900);
FORCEPROP 1 LAST PATH I246
J 0
(-3277 2025);
DISPLAY 0.872340 (-3277 2025);
PAINT GREEN (-3277 2025);
DISPLAY INVISIBLE (-3277 2025);
FORCEADD TAP..1
(-3275 1975);
FORCEPROP 3 LASTPIN (-3325 1975) SIG_NAME M_B_CPU0_SA_CB<6>
J 0
(-3315 1985);
DISPLAY 0.659574 (-3315 1985);
PAINT MONO (-3315 1985);
DISPLAY INVISIBLE (-3315 1985);
FORCEPROP 1 LASTPIN (-3325 1975) BN 6
J 0
(-3337 1983);
DISPLAY 0.489362 (-3337 1983);
PAINT GREEN (-3337 1983);
FORCEPROP 2 LAST CDS_LIB mstr_standard
J 2
(-3275 1975);
DISPLAY 0.723404 (-3275 1975);
PAINT MONO (-3275 1975);
DISPLAY INVISIBLE (-3275 1975);
FORCEPROP 1 LAST BODY_TYPE PLUMBING
J 0
(-3275 2025);
DISPLAY 0.872340 (-3275 2025);
PAINT GREEN (-3275 2025);
DISPLAY INVISIBLE (-3275 2025);
FORCEPROP 1 LAST HDL_TAP TRUE
J 0
(-2950 1850);
DISPLAY 0.872340 (-2950 1850);
DISPLAY INVISIBLE (-2950 1850);
FORCEPROP 1 LAST PATH I247
J 0
(-3277 1975);
DISPLAY 0.872340 (-3277 1975);
PAINT GREEN (-3277 1975);
DISPLAY INVISIBLE (-3277 1975);
FORCEADD TAP..1
(-3275 1825);
FORCEPROP 3 LASTPIN (-3325 1825) SIG_NAME M_B_CPU0_SB_CB<0>
J 0
(-3315 1835);
DISPLAY 0.659574 (-3315 1835);
PAINT MONO (-3315 1835);
DISPLAY INVISIBLE (-3315 1835);
FORCEPROP 1 LASTPIN (-3325 1825) BN 0
J 0
(-3337 1833);
DISPLAY 0.489362 (-3337 1833);
PAINT GREEN (-3337 1833);
FORCEPROP 2 LAST CDS_LIB mstr_standard
J 2
(-3275 1825);
DISPLAY 0.723404 (-3275 1825);
PAINT MONO (-3275 1825);
DISPLAY INVISIBLE (-3275 1825);
FORCEPROP 1 LAST BODY_TYPE PLUMBING
J 0
(-3275 1875);
DISPLAY 0.872340 (-3275 1875);
PAINT GREEN (-3275 1875);
DISPLAY INVISIBLE (-3275 1875);
FORCEPROP 1 LAST HDL_TAP TRUE
J 0
(-2950 1700);
DISPLAY 0.872340 (-2950 1700);
DISPLAY INVISIBLE (-2950 1700);
FORCEPROP 1 LAST PATH I248
J 0
(-3277 1825);
DISPLAY 0.872340 (-3277 1825);
PAINT GREEN (-3277 1825);
DISPLAY INVISIBLE (-3277 1825);
FORCEADD TAP..1
(-3275 1775);
FORCEPROP 3 LASTPIN (-3325 1775) SIG_NAME M_B_CPU0_SB_CB<1>
J 0
(-3315 1785);
DISPLAY 0.659574 (-3315 1785);
PAINT MONO (-3315 1785);
DISPLAY INVISIBLE (-3315 1785);
FORCEPROP 1 LASTPIN (-3325 1775) BN 1
J 0
(-3337 1783);
DISPLAY 0.489362 (-3337 1783);
PAINT GREEN (-3337 1783);
FORCEPROP 2 LAST CDS_LIB mstr_standard
J 2
(-3275 1775);
DISPLAY 0.723404 (-3275 1775);
PAINT MONO (-3275 1775);
DISPLAY INVISIBLE (-3275 1775);
FORCEPROP 1 LAST BODY_TYPE PLUMBING
J 0
(-3275 1825);
DISPLAY 0.872340 (-3275 1825);
PAINT GREEN (-3275 1825);
DISPLAY INVISIBLE (-3275 1825);
FORCEPROP 1 LAST HDL_TAP TRUE
J 0
(-2950 1650);
DISPLAY 0.872340 (-2950 1650);
DISPLAY INVISIBLE (-2950 1650);
FORCEPROP 1 LAST PATH I249
J 0
(-3277 1775);
DISPLAY 0.872340 (-3277 1775);
PAINT GREEN (-3277 1775);
DISPLAY INVISIBLE (-3277 1775);
FORCEADD TAP..1
(-3275 1725);
FORCEPROP 3 LASTPIN (-3325 1725) SIG_NAME M_B_CPU0_SB_CB<2>
J 0
(-3315 1735);
DISPLAY 0.659574 (-3315 1735);
PAINT MONO (-3315 1735);
DISPLAY INVISIBLE (-3315 1735);
FORCEPROP 1 LASTPIN (-3325 1725) BN 2
J 0
(-3337 1733);
DISPLAY 0.489362 (-3337 1733);
PAINT GREEN (-3337 1733);
FORCEPROP 2 LAST CDS_LIB mstr_standard
J 2
(-3275 1725);
DISPLAY 0.723404 (-3275 1725);
PAINT MONO (-3275 1725);
DISPLAY INVISIBLE (-3275 1725);
FORCEPROP 1 LAST BODY_TYPE PLUMBING
J 0
(-3275 1775);
DISPLAY 0.872340 (-3275 1775);
PAINT GREEN (-3275 1775);
DISPLAY INVISIBLE (-3275 1775);
FORCEPROP 1 LAST HDL_TAP TRUE
J 0
(-2950 1600);
DISPLAY 0.872340 (-2950 1600);
DISPLAY INVISIBLE (-2950 1600);
FORCEPROP 1 LAST PATH I250
J 0
(-3277 1725);
DISPLAY 0.872340 (-3277 1725);
PAINT GREEN (-3277 1725);
DISPLAY INVISIBLE (-3277 1725);
FORCEADD TAP..1
(-3275 1675);
FORCEPROP 3 LASTPIN (-3325 1675) SIG_NAME M_B_CPU0_SB_CB<3>
J 0
(-3315 1685);
DISPLAY 0.659574 (-3315 1685);
PAINT MONO (-3315 1685);
DISPLAY INVISIBLE (-3315 1685);
FORCEPROP 1 LASTPIN (-3325 1675) BN 3
J 0
(-3337 1683);
DISPLAY 0.489362 (-3337 1683);
PAINT GREEN (-3337 1683);
FORCEPROP 2 LAST CDS_LIB mstr_standard
J 2
(-3275 1675);
DISPLAY 0.723404 (-3275 1675);
PAINT MONO (-3275 1675);
DISPLAY INVISIBLE (-3275 1675);
FORCEPROP 1 LAST BODY_TYPE PLUMBING
J 0
(-3275 1725);
DISPLAY 0.872340 (-3275 1725);
PAINT GREEN (-3275 1725);
DISPLAY INVISIBLE (-3275 1725);
FORCEPROP 1 LAST HDL_TAP TRUE
J 0
(-2950 1550);
DISPLAY 0.872340 (-2950 1550);
DISPLAY INVISIBLE (-2950 1550);
FORCEPROP 1 LAST PATH I251
J 0
(-3277 1675);
DISPLAY 0.872340 (-3277 1675);
PAINT GREEN (-3277 1675);
DISPLAY INVISIBLE (-3277 1675);
FORCEADD TAP..1
(-3275 1625);
FORCEPROP 3 LASTPIN (-3325 1625) SIG_NAME M_B_CPU0_SB_CB<4>
J 0
(-3315 1635);
DISPLAY 0.659574 (-3315 1635);
PAINT MONO (-3315 1635);
DISPLAY INVISIBLE (-3315 1635);
FORCEPROP 1 LASTPIN (-3325 1625) BN 4
J 0
(-3337 1633);
DISPLAY 0.489362 (-3337 1633);
PAINT GREEN (-3337 1633);
FORCEPROP 2 LAST CDS_LIB mstr_standard
J 2
(-3275 1625);
DISPLAY 0.723404 (-3275 1625);
PAINT MONO (-3275 1625);
DISPLAY INVISIBLE (-3275 1625);
FORCEPROP 1 LAST BODY_TYPE PLUMBING
J 0
(-3275 1675);
DISPLAY 0.872340 (-3275 1675);
PAINT GREEN (-3275 1675);
DISPLAY INVISIBLE (-3275 1675);
FORCEPROP 1 LAST HDL_TAP TRUE
J 0
(-2950 1500);
DISPLAY 0.872340 (-2950 1500);
DISPLAY INVISIBLE (-2950 1500);
FORCEPROP 1 LAST PATH I252
J 0
(-3277 1625);
DISPLAY 0.872340 (-3277 1625);
PAINT GREEN (-3277 1625);
DISPLAY INVISIBLE (-3277 1625);
FORCEADD TAP..1
(-3275 1575);
FORCEPROP 3 LASTPIN (-3325 1575) SIG_NAME M_B_CPU0_SB_CB<5>
J 0
(-3315 1585);
DISPLAY 0.659574 (-3315 1585);
PAINT MONO (-3315 1585);
DISPLAY INVISIBLE (-3315 1585);
FORCEPROP 1 LASTPIN (-3325 1575) BN 5
J 0
(-3337 1583);
DISPLAY 0.489362 (-3337 1583);
PAINT GREEN (-3337 1583);
FORCEPROP 2 LAST CDS_LIB mstr_standard
J 2
(-3275 1575);
DISPLAY 0.723404 (-3275 1575);
PAINT MONO (-3275 1575);
DISPLAY INVISIBLE (-3275 1575);
FORCEPROP 1 LAST BODY_TYPE PLUMBING
J 0
(-3275 1625);
DISPLAY 0.872340 (-3275 1625);
PAINT GREEN (-3275 1625);
DISPLAY INVISIBLE (-3275 1625);
FORCEPROP 1 LAST HDL_TAP TRUE
J 0
(-2950 1450);
DISPLAY 0.872340 (-2950 1450);
DISPLAY INVISIBLE (-2950 1450);
FORCEPROP 1 LAST PATH I253
J 0
(-3277 1575);
DISPLAY 0.872340 (-3277 1575);
PAINT GREEN (-3277 1575);
DISPLAY INVISIBLE (-3277 1575);
FORCEADD TAP..1
(-3275 1475);
FORCEPROP 3 LASTPIN (-3325 1475) SIG_NAME M_B_CPU0_SB_CB<7>
J 0
(-3315 1485);
DISPLAY 0.659574 (-3315 1485);
PAINT MONO (-3315 1485);
DISPLAY INVISIBLE (-3315 1485);
FORCEPROP 1 LASTPIN (-3325 1475) BN 7
J 0
(-3337 1483);
DISPLAY 0.489362 (-3337 1483);
PAINT GREEN (-3337 1483);
FORCEPROP 2 LAST CDS_LIB mstr_standard
J 2
(-3275 1475);
DISPLAY 0.723404 (-3275 1475);
PAINT MONO (-3275 1475);
DISPLAY INVISIBLE (-3275 1475);
FORCEPROP 1 LAST BODY_TYPE PLUMBING
J 0
(-3275 1525);
DISPLAY 0.872340 (-3275 1525);
PAINT GREEN (-3275 1525);
DISPLAY INVISIBLE (-3275 1525);
FORCEPROP 1 LAST HDL_TAP TRUE
J 0
(-2950 1350);
DISPLAY 0.872340 (-2950 1350);
DISPLAY INVISIBLE (-2950 1350);
FORCEPROP 1 LAST PATH I254
J 0
(-3277 1475);
DISPLAY 0.872340 (-3277 1475);
PAINT GREEN (-3277 1475);
DISPLAY INVISIBLE (-3277 1475);
FORCEADD TAP..1
(-3275 1525);
FORCEPROP 3 LASTPIN (-3325 1525) SIG_NAME M_B_CPU0_SB_CB<6>
J 0
(-3315 1535);
DISPLAY 0.659574 (-3315 1535);
PAINT MONO (-3315 1535);
DISPLAY INVISIBLE (-3315 1535);
FORCEPROP 1 LASTPIN (-3325 1525) BN 6
J 0
(-3337 1533);
DISPLAY 0.489362 (-3337 1533);
PAINT GREEN (-3337 1533);
FORCEPROP 2 LAST CDS_LIB mstr_standard
J 2
(-3275 1525);
DISPLAY 0.723404 (-3275 1525);
PAINT MONO (-3275 1525);
DISPLAY INVISIBLE (-3275 1525);
FORCEPROP 1 LAST BODY_TYPE PLUMBING
J 0
(-3275 1575);
DISPLAY 0.872340 (-3275 1575);
PAINT GREEN (-3275 1575);
DISPLAY INVISIBLE (-3275 1575);
FORCEPROP 1 LAST HDL_TAP TRUE
J 0
(-2950 1400);
DISPLAY 0.872340 (-2950 1400);
DISPLAY INVISIBLE (-2950 1400);
FORCEPROP 1 LAST PATH I255
J 0
(-3277 1525);
DISPLAY 0.872340 (-3277 1525);
PAINT GREEN (-3277 1525);
DISPLAY INVISIBLE (-3277 1525);
FORCEADD TAP..1
R 2
(-5700 5875);
FORCEPROP 3 LASTPIN (-5650 5875) SIG_NAME M_B_CPU0_SA_DQS_DP<0>
J 0
(-5640 5885);
DISPLAY 0.659574 (-5640 5885);
PAINT MONO (-5640 5885);
DISPLAY INVISIBLE (-5640 5885);
FORCEPROP 1 LASTPIN (-5650 5875) BN 0
J 2
(-5638 5883);
DISPLAY 0.489362 (-5638 5883);
PAINT GREEN (-5638 5883);
FORCEPROP 2 LAST CDS_LIB mstr_standard
J 2
(-5700 5875);
DISPLAY 0.723404 (-5700 5875);
PAINT MONO (-5700 5875);
DISPLAY INVISIBLE (-5700 5875);
FORCEPROP 1 LAST BODY_TYPE PLUMBING
J 2
(-5700 5925);
DISPLAY 0.872340 (-5700 5925);
PAINT GREEN (-5700 5925);
DISPLAY INVISIBLE (-5700 5925);
FORCEPROP 1 LAST HDL_TAP TRUE
J 2
(-6025 5750);
DISPLAY 0.872340 (-6025 5750);
DISPLAY INVISIBLE (-6025 5750);
FORCEPROP 1 LAST PATH I256
J 2
(-5698 5875);
DISPLAY 0.872340 (-5698 5875);
PAINT GREEN (-5698 5875);
DISPLAY INVISIBLE (-5698 5875);
FORCEADD TAP..1
R 2
(-5700 5775);
FORCEPROP 3 LASTPIN (-5650 5775) SIG_NAME M_B_CPU0_SA_DQS_DP<1>
J 0
(-5640 5785);
DISPLAY 0.659574 (-5640 5785);
PAINT MONO (-5640 5785);
DISPLAY INVISIBLE (-5640 5785);
FORCEPROP 1 LASTPIN (-5650 5775) BN 1
J 2
(-5638 5783);
DISPLAY 0.489362 (-5638 5783);
PAINT GREEN (-5638 5783);
FORCEPROP 2 LAST CDS_LIB mstr_standard
J 2
(-5700 5775);
DISPLAY 0.723404 (-5700 5775);
PAINT MONO (-5700 5775);
DISPLAY INVISIBLE (-5700 5775);
FORCEPROP 1 LAST BODY_TYPE PLUMBING
J 2
(-5700 5825);
DISPLAY 0.872340 (-5700 5825);
PAINT GREEN (-5700 5825);
DISPLAY INVISIBLE (-5700 5825);
FORCEPROP 1 LAST HDL_TAP TRUE
J 2
(-6025 5650);
DISPLAY 0.872340 (-6025 5650);
DISPLAY INVISIBLE (-6025 5650);
FORCEPROP 1 LAST PATH I257
J 2
(-5698 5775);
DISPLAY 0.872340 (-5698 5775);
PAINT GREEN (-5698 5775);
DISPLAY INVISIBLE (-5698 5775);
FORCEADD TAP..1
R 2
(-5700 5675);
FORCEPROP 3 LASTPIN (-5650 5675) SIG_NAME M_B_CPU0_SA_DQS_DP<2>
J 0
(-5640 5685);
DISPLAY 0.659574 (-5640 5685);
PAINT MONO (-5640 5685);
DISPLAY INVISIBLE (-5640 5685);
FORCEPROP 1 LASTPIN (-5650 5675) BN 2
J 2
(-5638 5683);
DISPLAY 0.489362 (-5638 5683);
PAINT GREEN (-5638 5683);
FORCEPROP 2 LAST CDS_LIB mstr_standard
J 2
(-5700 5675);
DISPLAY 0.723404 (-5700 5675);
PAINT MONO (-5700 5675);
DISPLAY INVISIBLE (-5700 5675);
FORCEPROP 1 LAST BODY_TYPE PLUMBING
J 2
(-5700 5725);
DISPLAY 0.872340 (-5700 5725);
PAINT GREEN (-5700 5725);
DISPLAY INVISIBLE (-5700 5725);
FORCEPROP 1 LAST HDL_TAP TRUE
J 2
(-6025 5550);
DISPLAY 0.872340 (-6025 5550);
DISPLAY INVISIBLE (-6025 5550);
FORCEPROP 1 LAST PATH I258
J 2
(-5698 5675);
DISPLAY 0.872340 (-5698 5675);
PAINT GREEN (-5698 5675);
DISPLAY INVISIBLE (-5698 5675);
FORCEADD TAP..1
R 2
(-5900 5725);
FORCEPROP 3 LASTPIN (-5850 5725) SIG_NAME M_B_CPU0_SA_DQS_DN<1>
J 0
(-5840 5735);
DISPLAY 0.659574 (-5840 5735);
PAINT MONO (-5840 5735);
DISPLAY INVISIBLE (-5840 5735);
FORCEPROP 1 LASTPIN (-5850 5725) BN 1
J 2
(-5838 5733);
DISPLAY 0.489362 (-5838 5733);
PAINT GREEN (-5838 5733);
FORCEPROP 2 LAST CDS_LIB mstr_standard
J 2
(-5900 5725);
DISPLAY 0.723404 (-5900 5725);
PAINT MONO (-5900 5725);
DISPLAY INVISIBLE (-5900 5725);
FORCEPROP 1 LAST BODY_TYPE PLUMBING
J 2
(-5900 5775);
DISPLAY 0.872340 (-5900 5775);
PAINT GREEN (-5900 5775);
DISPLAY INVISIBLE (-5900 5775);
FORCEPROP 1 LAST HDL_TAP TRUE
J 2
(-6225 5600);
DISPLAY 0.872340 (-6225 5600);
DISPLAY INVISIBLE (-6225 5600);
FORCEPROP 1 LAST PATH I259
J 2
(-5898 5725);
DISPLAY 0.872340 (-5898 5725);
PAINT GREEN (-5898 5725);
DISPLAY INVISIBLE (-5898 5725);
FORCEADD TAP..1
R 2
(-5900 5825);
FORCEPROP 3 LASTPIN (-5850 5825) SIG_NAME M_B_CPU0_SA_DQS_DN<0>
J 0
(-5840 5835);
DISPLAY 0.659574 (-5840 5835);
PAINT MONO (-5840 5835);
DISPLAY INVISIBLE (-5840 5835);
FORCEPROP 1 LASTPIN (-5850 5825) BN 0
J 2
(-5838 5833);
DISPLAY 0.489362 (-5838 5833);
PAINT GREEN (-5838 5833);
FORCEPROP 2 LAST CDS_LIB mstr_standard
J 2
(-5900 5825);
DISPLAY 0.723404 (-5900 5825);
PAINT MONO (-5900 5825);
DISPLAY INVISIBLE (-5900 5825);
FORCEPROP 1 LAST BODY_TYPE PLUMBING
J 2
(-5900 5875);
DISPLAY 0.872340 (-5900 5875);
PAINT GREEN (-5900 5875);
DISPLAY INVISIBLE (-5900 5875);
FORCEPROP 1 LAST HDL_TAP TRUE
J 2
(-6225 5700);
DISPLAY 0.872340 (-6225 5700);
DISPLAY INVISIBLE (-6225 5700);
FORCEPROP 1 LAST PATH I260
J 2
(-5898 5825);
DISPLAY 0.872340 (-5898 5825);
PAINT GREEN (-5898 5825);
DISPLAY INVISIBLE (-5898 5825);
FORCEADD TAP..1
R 2
(-5700 5575);
FORCEPROP 3 LASTPIN (-5650 5575) SIG_NAME M_B_CPU0_SA_DQS_DP<3>
J 0
(-5640 5585);
DISPLAY 0.659574 (-5640 5585);
PAINT MONO (-5640 5585);
DISPLAY INVISIBLE (-5640 5585);
FORCEPROP 1 LASTPIN (-5650 5575) BN 3
J 2
(-5638 5583);
DISPLAY 0.489362 (-5638 5583);
PAINT GREEN (-5638 5583);
FORCEPROP 2 LAST CDS_LIB mstr_standard
J 2
(-5700 5575);
DISPLAY 0.723404 (-5700 5575);
PAINT MONO (-5700 5575);
DISPLAY INVISIBLE (-5700 5575);
FORCEPROP 1 LAST BODY_TYPE PLUMBING
J 2
(-5700 5625);
DISPLAY 0.872340 (-5700 5625);
PAINT GREEN (-5700 5625);
DISPLAY INVISIBLE (-5700 5625);
FORCEPROP 1 LAST HDL_TAP TRUE
J 2
(-6025 5450);
DISPLAY 0.872340 (-6025 5450);
DISPLAY INVISIBLE (-6025 5450);
FORCEPROP 1 LAST PATH I261
J 2
(-5698 5575);
DISPLAY 0.872340 (-5698 5575);
PAINT GREEN (-5698 5575);
DISPLAY INVISIBLE (-5698 5575);
FORCEADD TAP..1
R 2
(-5700 5375);
FORCEPROP 3 LASTPIN (-5650 5375) SIG_NAME M_B_CPU0_SA_DQS_DP<5>
J 0
(-5640 5385);
DISPLAY 0.659574 (-5640 5385);
PAINT MONO (-5640 5385);
DISPLAY INVISIBLE (-5640 5385);
FORCEPROP 1 LASTPIN (-5650 5375) BN 5
J 2
(-5638 5383);
DISPLAY 0.489362 (-5638 5383);
PAINT GREEN (-5638 5383);
FORCEPROP 2 LAST CDS_LIB mstr_standard
J 2
(-5700 5375);
DISPLAY 0.723404 (-5700 5375);
PAINT MONO (-5700 5375);
DISPLAY INVISIBLE (-5700 5375);
FORCEPROP 1 LAST BODY_TYPE PLUMBING
J 2
(-5700 5425);
DISPLAY 0.872340 (-5700 5425);
PAINT GREEN (-5700 5425);
DISPLAY INVISIBLE (-5700 5425);
FORCEPROP 1 LAST HDL_TAP TRUE
J 2
(-6025 5250);
DISPLAY 0.872340 (-6025 5250);
DISPLAY INVISIBLE (-6025 5250);
FORCEPROP 1 LAST PATH I262
J 2
(-5698 5375);
DISPLAY 0.872340 (-5698 5375);
PAINT GREEN (-5698 5375);
DISPLAY INVISIBLE (-5698 5375);
FORCEADD TAP..1
R 2
(-5700 5475);
FORCEPROP 3 LASTPIN (-5650 5475) SIG_NAME M_B_CPU0_SA_DQS_DP<4>
J 0
(-5640 5485);
DISPLAY 0.659574 (-5640 5485);
PAINT MONO (-5640 5485);
DISPLAY INVISIBLE (-5640 5485);
FORCEPROP 1 LASTPIN (-5650 5475) BN 4
J 2
(-5638 5483);
DISPLAY 0.489362 (-5638 5483);
PAINT GREEN (-5638 5483);
FORCEPROP 2 LAST CDS_LIB mstr_standard
J 2
(-5700 5475);
DISPLAY 0.723404 (-5700 5475);
PAINT MONO (-5700 5475);
DISPLAY INVISIBLE (-5700 5475);
FORCEPROP 1 LAST BODY_TYPE PLUMBING
J 2
(-5700 5525);
DISPLAY 0.872340 (-5700 5525);
PAINT GREEN (-5700 5525);
DISPLAY INVISIBLE (-5700 5525);
FORCEPROP 1 LAST HDL_TAP TRUE
J 2
(-6025 5350);
DISPLAY 0.872340 (-6025 5350);
DISPLAY INVISIBLE (-6025 5350);
FORCEPROP 1 LAST PATH I263
J 2
(-5698 5475);
DISPLAY 0.872340 (-5698 5475);
PAINT GREEN (-5698 5475);
DISPLAY INVISIBLE (-5698 5475);
FORCEADD TAP..1
R 2
(-5900 5425);
FORCEPROP 3 LASTPIN (-5850 5425) SIG_NAME M_B_CPU0_SA_DQS_DN<4>
J 0
(-5840 5435);
DISPLAY 0.659574 (-5840 5435);
PAINT MONO (-5840 5435);
DISPLAY INVISIBLE (-5840 5435);
FORCEPROP 1 LASTPIN (-5850 5425) BN 4
J 2
(-5838 5433);
DISPLAY 0.489362 (-5838 5433);
PAINT GREEN (-5838 5433);
FORCEPROP 2 LAST CDS_LIB mstr_standard
J 2
(-5900 5425);
DISPLAY 0.723404 (-5900 5425);
PAINT MONO (-5900 5425);
DISPLAY INVISIBLE (-5900 5425);
FORCEPROP 1 LAST BODY_TYPE PLUMBING
J 2
(-5900 5475);
DISPLAY 0.872340 (-5900 5475);
PAINT GREEN (-5900 5475);
DISPLAY INVISIBLE (-5900 5475);
FORCEPROP 1 LAST HDL_TAP TRUE
J 2
(-6225 5300);
DISPLAY 0.872340 (-6225 5300);
DISPLAY INVISIBLE (-6225 5300);
FORCEPROP 1 LAST PATH I264
J 2
(-5898 5425);
DISPLAY 0.872340 (-5898 5425);
PAINT GREEN (-5898 5425);
DISPLAY INVISIBLE (-5898 5425);
FORCEADD TAP..1
R 2
(-5900 5625);
FORCEPROP 3 LASTPIN (-5850 5625) SIG_NAME M_B_CPU0_SA_DQS_DN<2>
J 0
(-5840 5635);
DISPLAY 0.659574 (-5840 5635);
PAINT MONO (-5840 5635);
DISPLAY INVISIBLE (-5840 5635);
FORCEPROP 1 LASTPIN (-5850 5625) BN 2
J 2
(-5838 5633);
DISPLAY 0.489362 (-5838 5633);
PAINT GREEN (-5838 5633);
FORCEPROP 2 LAST CDS_LIB mstr_standard
J 2
(-5900 5625);
DISPLAY 0.723404 (-5900 5625);
PAINT MONO (-5900 5625);
DISPLAY INVISIBLE (-5900 5625);
FORCEPROP 1 LAST BODY_TYPE PLUMBING
J 2
(-5900 5675);
DISPLAY 0.872340 (-5900 5675);
PAINT GREEN (-5900 5675);
DISPLAY INVISIBLE (-5900 5675);
FORCEPROP 1 LAST HDL_TAP TRUE
J 2
(-6225 5500);
DISPLAY 0.872340 (-6225 5500);
DISPLAY INVISIBLE (-6225 5500);
FORCEPROP 1 LAST PATH I265
J 2
(-5898 5625);
DISPLAY 0.872340 (-5898 5625);
PAINT GREEN (-5898 5625);
DISPLAY INVISIBLE (-5898 5625);
FORCEADD TAP..1
R 2
(-5900 5525);
FORCEPROP 3 LASTPIN (-5850 5525) SIG_NAME M_B_CPU0_SA_DQS_DN<3>
J 0
(-5840 5535);
DISPLAY 0.659574 (-5840 5535);
PAINT MONO (-5840 5535);
DISPLAY INVISIBLE (-5840 5535);
FORCEPROP 1 LASTPIN (-5850 5525) BN 3
J 2
(-5838 5533);
DISPLAY 0.489362 (-5838 5533);
PAINT GREEN (-5838 5533);
FORCEPROP 2 LAST CDS_LIB mstr_standard
J 2
(-5900 5525);
DISPLAY 0.723404 (-5900 5525);
PAINT MONO (-5900 5525);
DISPLAY INVISIBLE (-5900 5525);
FORCEPROP 1 LAST BODY_TYPE PLUMBING
J 2
(-5900 5575);
DISPLAY 0.872340 (-5900 5575);
PAINT GREEN (-5900 5575);
DISPLAY INVISIBLE (-5900 5575);
FORCEPROP 1 LAST HDL_TAP TRUE
J 2
(-6225 5400);
DISPLAY 0.872340 (-6225 5400);
DISPLAY INVISIBLE (-6225 5400);
FORCEPROP 1 LAST PATH I266
J 2
(-5898 5525);
DISPLAY 0.872340 (-5898 5525);
PAINT GREEN (-5898 5525);
DISPLAY INVISIBLE (-5898 5525);
FORCEADD TAP..1
R 2
(-5700 5175);
FORCEPROP 3 LASTPIN (-5650 5175) SIG_NAME M_B_CPU0_SA_DQS_DP<7>
J 0
(-5640 5185);
DISPLAY 0.659574 (-5640 5185);
PAINT MONO (-5640 5185);
DISPLAY INVISIBLE (-5640 5185);
FORCEPROP 1 LASTPIN (-5650 5175) BN 7
J 2
(-5638 5183);
DISPLAY 0.489362 (-5638 5183);
PAINT GREEN (-5638 5183);
FORCEPROP 2 LAST CDS_LIB mstr_standard
J 2
(-5700 5175);
DISPLAY 0.723404 (-5700 5175);
PAINT MONO (-5700 5175);
DISPLAY INVISIBLE (-5700 5175);
FORCEPROP 1 LAST BODY_TYPE PLUMBING
J 2
(-5700 5225);
DISPLAY 0.872340 (-5700 5225);
PAINT GREEN (-5700 5225);
DISPLAY INVISIBLE (-5700 5225);
FORCEPROP 1 LAST HDL_TAP TRUE
J 2
(-6025 5050);
DISPLAY 0.872340 (-6025 5050);
DISPLAY INVISIBLE (-6025 5050);
FORCEPROP 1 LAST PATH I267
J 2
(-5698 5175);
DISPLAY 0.872340 (-5698 5175);
PAINT GREEN (-5698 5175);
DISPLAY INVISIBLE (-5698 5175);
FORCEADD TAP..1
R 2
(-5700 5275);
FORCEPROP 3 LASTPIN (-5650 5275) SIG_NAME M_B_CPU0_SA_DQS_DP<6>
J 0
(-5640 5285);
DISPLAY 0.659574 (-5640 5285);
PAINT MONO (-5640 5285);
DISPLAY INVISIBLE (-5640 5285);
FORCEPROP 1 LASTPIN (-5650 5275) BN 6
J 2
(-5638 5283);
DISPLAY 0.489362 (-5638 5283);
PAINT GREEN (-5638 5283);
FORCEPROP 2 LAST CDS_LIB mstr_standard
J 2
(-5700 5275);
DISPLAY 0.723404 (-5700 5275);
PAINT MONO (-5700 5275);
DISPLAY INVISIBLE (-5700 5275);
FORCEPROP 1 LAST BODY_TYPE PLUMBING
J 2
(-5700 5325);
DISPLAY 0.872340 (-5700 5325);
PAINT GREEN (-5700 5325);
DISPLAY INVISIBLE (-5700 5325);
FORCEPROP 1 LAST HDL_TAP TRUE
J 2
(-6025 5150);
DISPLAY 0.872340 (-6025 5150);
DISPLAY INVISIBLE (-6025 5150);
FORCEPROP 1 LAST PATH I268
J 2
(-5698 5275);
DISPLAY 0.872340 (-5698 5275);
PAINT GREEN (-5698 5275);
DISPLAY INVISIBLE (-5698 5275);
FORCEADD TAP..1
R 2
(-5900 5325);
FORCEPROP 3 LASTPIN (-5850 5325) SIG_NAME M_B_CPU0_SA_DQS_DN<5>
J 0
(-5840 5335);
DISPLAY 0.659574 (-5840 5335);
PAINT MONO (-5840 5335);
DISPLAY INVISIBLE (-5840 5335);
FORCEPROP 1 LASTPIN (-5850 5325) BN 5
J 2
(-5838 5333);
DISPLAY 0.489362 (-5838 5333);
PAINT GREEN (-5838 5333);
FORCEPROP 2 LAST CDS_LIB mstr_standard
J 2
(-5900 5325);
DISPLAY 0.723404 (-5900 5325);
PAINT MONO (-5900 5325);
DISPLAY INVISIBLE (-5900 5325);
FORCEPROP 1 LAST BODY_TYPE PLUMBING
J 2
(-5900 5375);
DISPLAY 0.872340 (-5900 5375);
PAINT GREEN (-5900 5375);
DISPLAY INVISIBLE (-5900 5375);
FORCEPROP 1 LAST HDL_TAP TRUE
J 2
(-6225 5200);
DISPLAY 0.872340 (-6225 5200);
DISPLAY INVISIBLE (-6225 5200);
FORCEPROP 1 LAST PATH I269
J 2
(-5898 5325);
DISPLAY 0.872340 (-5898 5325);
PAINT GREEN (-5898 5325);
DISPLAY INVISIBLE (-5898 5325);
FORCEADD TAP..1
R 2
(-5900 5225);
FORCEPROP 3 LASTPIN (-5850 5225) SIG_NAME M_B_CPU0_SA_DQS_DN<6>
J 0
(-5840 5235);
DISPLAY 0.659574 (-5840 5235);
PAINT MONO (-5840 5235);
DISPLAY INVISIBLE (-5840 5235);
FORCEPROP 1 LASTPIN (-5850 5225) BN 6
J 2
(-5838 5233);
DISPLAY 0.489362 (-5838 5233);
PAINT GREEN (-5838 5233);
FORCEPROP 2 LAST CDS_LIB mstr_standard
J 2
(-5900 5225);
DISPLAY 0.723404 (-5900 5225);
PAINT MONO (-5900 5225);
DISPLAY INVISIBLE (-5900 5225);
FORCEPROP 1 LAST BODY_TYPE PLUMBING
J 2
(-5900 5275);
DISPLAY 0.872340 (-5900 5275);
PAINT GREEN (-5900 5275);
DISPLAY INVISIBLE (-5900 5275);
FORCEPROP 1 LAST HDL_TAP TRUE
J 2
(-6225 5100);
DISPLAY 0.872340 (-6225 5100);
DISPLAY INVISIBLE (-6225 5100);
FORCEPROP 1 LAST PATH I270
J 2
(-5898 5225);
DISPLAY 0.872340 (-5898 5225);
PAINT GREEN (-5898 5225);
DISPLAY INVISIBLE (-5898 5225);
FORCEADD TAP..1
R 2
(-5900 5125);
FORCEPROP 3 LASTPIN (-5850 5125) SIG_NAME M_B_CPU0_SA_DQS_DN<7>
J 0
(-5840 5135);
DISPLAY 0.659574 (-5840 5135);
PAINT MONO (-5840 5135);
DISPLAY INVISIBLE (-5840 5135);
FORCEPROP 1 LASTPIN (-5850 5125) BN 7
J 2
(-5838 5133);
DISPLAY 0.489362 (-5838 5133);
PAINT GREEN (-5838 5133);
FORCEPROP 2 LAST CDS_LIB mstr_standard
J 2
(-5900 5125);
DISPLAY 0.723404 (-5900 5125);
PAINT MONO (-5900 5125);
DISPLAY INVISIBLE (-5900 5125);
FORCEPROP 1 LAST BODY_TYPE PLUMBING
J 2
(-5900 5175);
DISPLAY 0.872340 (-5900 5175);
PAINT GREEN (-5900 5175);
DISPLAY INVISIBLE (-5900 5175);
FORCEPROP 1 LAST HDL_TAP TRUE
J 2
(-6225 5000);
DISPLAY 0.872340 (-6225 5000);
DISPLAY INVISIBLE (-6225 5000);
FORCEPROP 1 LAST PATH I271
J 2
(-5898 5125);
DISPLAY 0.872340 (-5898 5125);
PAINT GREEN (-5898 5125);
DISPLAY INVISIBLE (-5898 5125);
FORCEADD TAP..1
R 2
(-5700 4975);
FORCEPROP 3 LASTPIN (-5650 4975) SIG_NAME M_B_CPU0_SA_DQS_DP<9>
J 0
(-5640 4985);
DISPLAY 0.659574 (-5640 4985);
PAINT MONO (-5640 4985);
DISPLAY INVISIBLE (-5640 4985);
FORCEPROP 1 LASTPIN (-5650 4975) BN 9
J 2
(-5638 4983);
DISPLAY 0.489362 (-5638 4983);
PAINT GREEN (-5638 4983);
FORCEPROP 2 LAST CDS_LIB mstr_standard
J 2
(-5700 4975);
DISPLAY 0.723404 (-5700 4975);
PAINT MONO (-5700 4975);
DISPLAY INVISIBLE (-5700 4975);
FORCEPROP 1 LAST BODY_TYPE PLUMBING
J 2
(-5700 5025);
DISPLAY 0.872340 (-5700 5025);
PAINT GREEN (-5700 5025);
DISPLAY INVISIBLE (-5700 5025);
FORCEPROP 1 LAST HDL_TAP TRUE
J 2
(-6025 4850);
DISPLAY 0.872340 (-6025 4850);
DISPLAY INVISIBLE (-6025 4850);
FORCEPROP 1 LAST PATH I272
J 2
(-5698 4975);
DISPLAY 0.872340 (-5698 4975);
PAINT GREEN (-5698 4975);
DISPLAY INVISIBLE (-5698 4975);
FORCEADD TAP..1
R 2
(-5700 5075);
FORCEPROP 3 LASTPIN (-5650 5075) SIG_NAME M_B_CPU0_SA_DQS_DP<8>
J 0
(-5640 5085);
DISPLAY 0.659574 (-5640 5085);
PAINT MONO (-5640 5085);
DISPLAY INVISIBLE (-5640 5085);
FORCEPROP 1 LASTPIN (-5650 5075) BN 8
J 2
(-5638 5083);
DISPLAY 0.489362 (-5638 5083);
PAINT GREEN (-5638 5083);
FORCEPROP 2 LAST CDS_LIB mstr_standard
J 2
(-5700 5075);
DISPLAY 0.723404 (-5700 5075);
PAINT MONO (-5700 5075);
DISPLAY INVISIBLE (-5700 5075);
FORCEPROP 1 LAST BODY_TYPE PLUMBING
J 2
(-5700 5125);
DISPLAY 0.872340 (-5700 5125);
PAINT GREEN (-5700 5125);
DISPLAY INVISIBLE (-5700 5125);
FORCEPROP 1 LAST HDL_TAP TRUE
J 2
(-6025 4950);
DISPLAY 0.872340 (-6025 4950);
DISPLAY INVISIBLE (-6025 4950);
FORCEPROP 1 LAST PATH I273
J 2
(-5698 5075);
DISPLAY 0.872340 (-5698 5075);
PAINT GREEN (-5698 5075);
DISPLAY INVISIBLE (-5698 5075);
FORCEADD TAP..1
R 2
(-5900 5025);
FORCEPROP 3 LASTPIN (-5850 5025) SIG_NAME M_B_CPU0_SA_DQS_DN<8>
J 0
(-5840 5035);
DISPLAY 0.659574 (-5840 5035);
PAINT MONO (-5840 5035);
DISPLAY INVISIBLE (-5840 5035);
FORCEPROP 1 LASTPIN (-5850 5025) BN 8
J 2
(-5838 5033);
DISPLAY 0.489362 (-5838 5033);
PAINT GREEN (-5838 5033);
FORCEPROP 2 LAST CDS_LIB mstr_standard
J 2
(-5900 5025);
DISPLAY 0.723404 (-5900 5025);
PAINT MONO (-5900 5025);
DISPLAY INVISIBLE (-5900 5025);
FORCEPROP 1 LAST BODY_TYPE PLUMBING
J 2
(-5900 5075);
DISPLAY 0.872340 (-5900 5075);
PAINT GREEN (-5900 5075);
DISPLAY INVISIBLE (-5900 5075);
FORCEPROP 1 LAST HDL_TAP TRUE
J 2
(-6225 4900);
DISPLAY 0.872340 (-6225 4900);
DISPLAY INVISIBLE (-6225 4900);
FORCEPROP 1 LAST PATH I274
J 2
(-5898 5025);
DISPLAY 0.872340 (-5898 5025);
PAINT GREEN (-5898 5025);
DISPLAY INVISIBLE (-5898 5025);
FORCEADD TAP..1
R 2
(-5900 4925);
FORCEPROP 3 LASTPIN (-5850 4925) SIG_NAME M_B_CPU0_SA_DQS_DN<9>
J 0
(-5840 4935);
DISPLAY 0.659574 (-5840 4935);
PAINT MONO (-5840 4935);
DISPLAY INVISIBLE (-5840 4935);
FORCEPROP 1 LASTPIN (-5850 4925) BN 9
J 2
(-5838 4933);
DISPLAY 0.489362 (-5838 4933);
PAINT GREEN (-5838 4933);
FORCEPROP 2 LAST CDS_LIB mstr_standard
J 2
(-5900 4925);
DISPLAY 0.723404 (-5900 4925);
PAINT MONO (-5900 4925);
DISPLAY INVISIBLE (-5900 4925);
FORCEPROP 1 LAST BODY_TYPE PLUMBING
J 2
(-5900 4975);
DISPLAY 0.872340 (-5900 4975);
PAINT GREEN (-5900 4975);
DISPLAY INVISIBLE (-5900 4975);
FORCEPROP 1 LAST HDL_TAP TRUE
J 2
(-6225 4800);
DISPLAY 0.872340 (-6225 4800);
DISPLAY INVISIBLE (-6225 4800);
FORCEPROP 1 LAST PATH I275
J 2
(-5898 4925);
DISPLAY 0.872340 (-5898 4925);
PAINT GREEN (-5898 4925);
DISPLAY INVISIBLE (-5898 4925);
FORCEADD TAP..1
R 2
(-5700 4625);
FORCEPROP 3 LASTPIN (-5650 4625) SIG_NAME M_B_CPU0_SB_DQS_DP<2>
J 0
(-5640 4635);
DISPLAY 0.659574 (-5640 4635);
PAINT MONO (-5640 4635);
DISPLAY INVISIBLE (-5640 4635);
FORCEPROP 1 LASTPIN (-5650 4625) BN 2
J 2
(-5638 4633);
DISPLAY 0.489362 (-5638 4633);
PAINT GREEN (-5638 4633);
FORCEPROP 2 LAST CDS_LIB mstr_standard
J 2
(-5700 4625);
DISPLAY 0.723404 (-5700 4625);
PAINT MONO (-5700 4625);
DISPLAY INVISIBLE (-5700 4625);
FORCEPROP 1 LAST BODY_TYPE PLUMBING
J 2
(-5700 4675);
DISPLAY 0.872340 (-5700 4675);
PAINT GREEN (-5700 4675);
DISPLAY INVISIBLE (-5700 4675);
FORCEPROP 1 LAST HDL_TAP TRUE
J 2
(-6025 4500);
DISPLAY 0.872340 (-6025 4500);
DISPLAY INVISIBLE (-6025 4500);
FORCEPROP 1 LAST PATH I276
J 2
(-5698 4625);
DISPLAY 0.872340 (-5698 4625);
PAINT GREEN (-5698 4625);
DISPLAY INVISIBLE (-5698 4625);
FORCEADD TAP..1
R 2
(-5700 4825);
FORCEPROP 3 LASTPIN (-5650 4825) SIG_NAME M_B_CPU0_SB_DQS_DP<0>
J 0
(-5640 4835);
DISPLAY 0.659574 (-5640 4835);
PAINT MONO (-5640 4835);
DISPLAY INVISIBLE (-5640 4835);
FORCEPROP 1 LASTPIN (-5650 4825) BN 0
J 2
(-5638 4833);
DISPLAY 0.489362 (-5638 4833);
PAINT GREEN (-5638 4833);
FORCEPROP 2 LAST CDS_LIB mstr_standard
J 2
(-5700 4825);
DISPLAY 0.723404 (-5700 4825);
PAINT MONO (-5700 4825);
DISPLAY INVISIBLE (-5700 4825);
FORCEPROP 1 LAST BODY_TYPE PLUMBING
J 2
(-5700 4875);
DISPLAY 0.872340 (-5700 4875);
PAINT GREEN (-5700 4875);
DISPLAY INVISIBLE (-5700 4875);
FORCEPROP 1 LAST HDL_TAP TRUE
J 2
(-6025 4700);
DISPLAY 0.872340 (-6025 4700);
DISPLAY INVISIBLE (-6025 4700);
FORCEPROP 1 LAST PATH I277
J 2
(-5698 4825);
DISPLAY 0.872340 (-5698 4825);
PAINT GREEN (-5698 4825);
DISPLAY INVISIBLE (-5698 4825);
FORCEADD TAP..1
R 2
(-5700 4725);
FORCEPROP 3 LASTPIN (-5650 4725) SIG_NAME M_B_CPU0_SB_DQS_DP<1>
J 0
(-5640 4735);
DISPLAY 0.659574 (-5640 4735);
PAINT MONO (-5640 4735);
DISPLAY INVISIBLE (-5640 4735);
FORCEPROP 1 LASTPIN (-5650 4725) BN 1
J 2
(-5638 4733);
DISPLAY 0.489362 (-5638 4733);
PAINT GREEN (-5638 4733);
FORCEPROP 2 LAST CDS_LIB mstr_standard
J 2
(-5700 4725);
DISPLAY 0.723404 (-5700 4725);
PAINT MONO (-5700 4725);
DISPLAY INVISIBLE (-5700 4725);
FORCEPROP 1 LAST BODY_TYPE PLUMBING
J 2
(-5700 4775);
DISPLAY 0.872340 (-5700 4775);
PAINT GREEN (-5700 4775);
DISPLAY INVISIBLE (-5700 4775);
FORCEPROP 1 LAST HDL_TAP TRUE
J 2
(-6025 4600);
DISPLAY 0.872340 (-6025 4600);
DISPLAY INVISIBLE (-6025 4600);
FORCEPROP 1 LAST PATH I278
J 2
(-5698 4725);
DISPLAY 0.872340 (-5698 4725);
PAINT GREEN (-5698 4725);
DISPLAY INVISIBLE (-5698 4725);
FORCEADD TAP..1
R 2
(-5900 4675);
FORCEPROP 3 LASTPIN (-5850 4675) SIG_NAME M_B_CPU0_SB_DQS_DN<1>
J 0
(-5840 4685);
DISPLAY 0.659574 (-5840 4685);
PAINT MONO (-5840 4685);
DISPLAY INVISIBLE (-5840 4685);
FORCEPROP 1 LASTPIN (-5850 4675) BN 1
J 2
(-5838 4683);
DISPLAY 0.489362 (-5838 4683);
PAINT GREEN (-5838 4683);
FORCEPROP 2 LAST CDS_LIB mstr_standard
J 2
(-5900 4675);
DISPLAY 0.723404 (-5900 4675);
PAINT MONO (-5900 4675);
DISPLAY INVISIBLE (-5900 4675);
FORCEPROP 1 LAST BODY_TYPE PLUMBING
J 2
(-5900 4725);
DISPLAY 0.872340 (-5900 4725);
PAINT GREEN (-5900 4725);
DISPLAY INVISIBLE (-5900 4725);
FORCEPROP 1 LAST HDL_TAP TRUE
J 2
(-6225 4550);
DISPLAY 0.872340 (-6225 4550);
DISPLAY INVISIBLE (-6225 4550);
FORCEPROP 1 LAST PATH I279
J 2
(-5898 4675);
DISPLAY 0.872340 (-5898 4675);
PAINT GREEN (-5898 4675);
DISPLAY INVISIBLE (-5898 4675);
FORCEADD TAP..1
R 2
(-5900 4775);
FORCEPROP 3 LASTPIN (-5850 4775) SIG_NAME M_B_CPU0_SB_DQS_DN<0>
J 0
(-5840 4785);
DISPLAY 0.659574 (-5840 4785);
PAINT MONO (-5840 4785);
DISPLAY INVISIBLE (-5840 4785);
FORCEPROP 1 LASTPIN (-5850 4775) BN 0
J 2
(-5838 4783);
DISPLAY 0.489362 (-5838 4783);
PAINT GREEN (-5838 4783);
FORCEPROP 2 LAST CDS_LIB mstr_standard
J 2
(-5900 4775);
DISPLAY 0.723404 (-5900 4775);
PAINT MONO (-5900 4775);
DISPLAY INVISIBLE (-5900 4775);
FORCEPROP 1 LAST BODY_TYPE PLUMBING
J 2
(-5900 4825);
DISPLAY 0.872340 (-5900 4825);
PAINT GREEN (-5900 4825);
DISPLAY INVISIBLE (-5900 4825);
FORCEPROP 1 LAST HDL_TAP TRUE
J 2
(-6225 4650);
DISPLAY 0.872340 (-6225 4650);
DISPLAY INVISIBLE (-6225 4650);
FORCEPROP 1 LAST PATH I280
J 2
(-5898 4775);
DISPLAY 0.872340 (-5898 4775);
PAINT GREEN (-5898 4775);
DISPLAY INVISIBLE (-5898 4775);
FORCEADD TAP..1
R 2
(-5700 4525);
FORCEPROP 3 LASTPIN (-5650 4525) SIG_NAME M_B_CPU0_SB_DQS_DP<3>
J 0
(-5640 4535);
DISPLAY 0.659574 (-5640 4535);
PAINT MONO (-5640 4535);
DISPLAY INVISIBLE (-5640 4535);
FORCEPROP 1 LASTPIN (-5650 4525) BN 3
J 2
(-5638 4533);
DISPLAY 0.489362 (-5638 4533);
PAINT GREEN (-5638 4533);
FORCEPROP 2 LAST CDS_LIB mstr_standard
J 2
(-5700 4525);
DISPLAY 0.723404 (-5700 4525);
PAINT MONO (-5700 4525);
DISPLAY INVISIBLE (-5700 4525);
FORCEPROP 1 LAST BODY_TYPE PLUMBING
J 2
(-5700 4575);
DISPLAY 0.872340 (-5700 4575);
PAINT GREEN (-5700 4575);
DISPLAY INVISIBLE (-5700 4575);
FORCEPROP 1 LAST HDL_TAP TRUE
J 2
(-6025 4400);
DISPLAY 0.872340 (-6025 4400);
DISPLAY INVISIBLE (-6025 4400);
FORCEPROP 1 LAST PATH I281
J 2
(-5698 4525);
DISPLAY 0.872340 (-5698 4525);
PAINT GREEN (-5698 4525);
DISPLAY INVISIBLE (-5698 4525);
FORCEADD TAP..1
R 2
(-5700 4425);
FORCEPROP 3 LASTPIN (-5650 4425) SIG_NAME M_B_CPU0_SB_DQS_DP<4>
J 0
(-5640 4435);
DISPLAY 0.659574 (-5640 4435);
PAINT MONO (-5640 4435);
DISPLAY INVISIBLE (-5640 4435);
FORCEPROP 1 LASTPIN (-5650 4425) BN 4
J 2
(-5638 4433);
DISPLAY 0.489362 (-5638 4433);
PAINT GREEN (-5638 4433);
FORCEPROP 2 LAST CDS_LIB mstr_standard
J 2
(-5700 4425);
DISPLAY 0.723404 (-5700 4425);
PAINT MONO (-5700 4425);
DISPLAY INVISIBLE (-5700 4425);
FORCEPROP 1 LAST BODY_TYPE PLUMBING
J 2
(-5700 4475);
DISPLAY 0.872340 (-5700 4475);
PAINT GREEN (-5700 4475);
DISPLAY INVISIBLE (-5700 4475);
FORCEPROP 1 LAST HDL_TAP TRUE
J 2
(-6025 4300);
DISPLAY 0.872340 (-6025 4300);
DISPLAY INVISIBLE (-6025 4300);
FORCEPROP 1 LAST PATH I282
J 2
(-5698 4425);
DISPLAY 0.872340 (-5698 4425);
PAINT GREEN (-5698 4425);
DISPLAY INVISIBLE (-5698 4425);
FORCEADD TAP..1
R 2
(-5900 4575);
FORCEPROP 3 LASTPIN (-5850 4575) SIG_NAME M_B_CPU0_SB_DQS_DN<2>
J 0
(-5840 4585);
DISPLAY 0.659574 (-5840 4585);
PAINT MONO (-5840 4585);
DISPLAY INVISIBLE (-5840 4585);
FORCEPROP 1 LASTPIN (-5850 4575) BN 2
J 2
(-5838 4583);
DISPLAY 0.489362 (-5838 4583);
PAINT GREEN (-5838 4583);
FORCEPROP 2 LAST CDS_LIB mstr_standard
J 2
(-5900 4575);
DISPLAY 0.723404 (-5900 4575);
PAINT MONO (-5900 4575);
DISPLAY INVISIBLE (-5900 4575);
FORCEPROP 1 LAST BODY_TYPE PLUMBING
J 2
(-5900 4625);
DISPLAY 0.872340 (-5900 4625);
PAINT GREEN (-5900 4625);
DISPLAY INVISIBLE (-5900 4625);
FORCEPROP 1 LAST HDL_TAP TRUE
J 2
(-6225 4450);
DISPLAY 0.872340 (-6225 4450);
DISPLAY INVISIBLE (-6225 4450);
FORCEPROP 1 LAST PATH I283
J 2
(-5898 4575);
DISPLAY 0.872340 (-5898 4575);
PAINT GREEN (-5898 4575);
DISPLAY INVISIBLE (-5898 4575);
FORCEADD TAP..1
R 2
(-5900 4475);
FORCEPROP 3 LASTPIN (-5850 4475) SIG_NAME M_B_CPU0_SB_DQS_DN<3>
J 0
(-5840 4485);
DISPLAY 0.659574 (-5840 4485);
PAINT MONO (-5840 4485);
DISPLAY INVISIBLE (-5840 4485);
FORCEPROP 1 LASTPIN (-5850 4475) BN 3
J 2
(-5838 4483);
DISPLAY 0.489362 (-5838 4483);
PAINT GREEN (-5838 4483);
FORCEPROP 2 LAST CDS_LIB mstr_standard
J 2
(-5900 4475);
DISPLAY 0.723404 (-5900 4475);
PAINT MONO (-5900 4475);
DISPLAY INVISIBLE (-5900 4475);
FORCEPROP 1 LAST BODY_TYPE PLUMBING
J 2
(-5900 4525);
DISPLAY 0.872340 (-5900 4525);
PAINT GREEN (-5900 4525);
DISPLAY INVISIBLE (-5900 4525);
FORCEPROP 1 LAST HDL_TAP TRUE
J 2
(-6225 4350);
DISPLAY 0.872340 (-6225 4350);
DISPLAY INVISIBLE (-6225 4350);
FORCEPROP 1 LAST PATH I284
J 2
(-5898 4475);
DISPLAY 0.872340 (-5898 4475);
PAINT GREEN (-5898 4475);
DISPLAY INVISIBLE (-5898 4475);
FORCEADD TAP..1
R 2
(-5900 4375);
FORCEPROP 3 LASTPIN (-5850 4375) SIG_NAME M_B_CPU0_SB_DQS_DN<4>
J 0
(-5840 4385);
DISPLAY 0.659574 (-5840 4385);
PAINT MONO (-5840 4385);
DISPLAY INVISIBLE (-5840 4385);
FORCEPROP 1 LASTPIN (-5850 4375) BN 4
J 2
(-5838 4383);
DISPLAY 0.489362 (-5838 4383);
PAINT GREEN (-5838 4383);
FORCEPROP 2 LAST CDS_LIB mstr_standard
J 2
(-5900 4375);
DISPLAY 0.723404 (-5900 4375);
PAINT MONO (-5900 4375);
DISPLAY INVISIBLE (-5900 4375);
FORCEPROP 1 LAST BODY_TYPE PLUMBING
J 2
(-5900 4425);
DISPLAY 0.872340 (-5900 4425);
PAINT GREEN (-5900 4425);
DISPLAY INVISIBLE (-5900 4425);
FORCEPROP 1 LAST HDL_TAP TRUE
J 2
(-6225 4250);
DISPLAY 0.872340 (-6225 4250);
DISPLAY INVISIBLE (-6225 4250);
FORCEPROP 1 LAST PATH I285
J 2
(-5898 4375);
DISPLAY 0.872340 (-5898 4375);
PAINT GREEN (-5898 4375);
DISPLAY INVISIBLE (-5898 4375);
FORCEADD TAP..1
R 2
(-5700 4225);
FORCEPROP 3 LASTPIN (-5650 4225) SIG_NAME M_B_CPU0_SB_DQS_DP<6>
J 0
(-5640 4235);
DISPLAY 0.659574 (-5640 4235);
PAINT MONO (-5640 4235);
DISPLAY INVISIBLE (-5640 4235);
FORCEPROP 1 LASTPIN (-5650 4225) BN 6
J 2
(-5638 4233);
DISPLAY 0.489362 (-5638 4233);
PAINT GREEN (-5638 4233);
FORCEPROP 2 LAST CDS_LIB mstr_standard
J 2
(-5700 4225);
DISPLAY 0.723404 (-5700 4225);
PAINT MONO (-5700 4225);
DISPLAY INVISIBLE (-5700 4225);
FORCEPROP 1 LAST BODY_TYPE PLUMBING
J 2
(-5700 4275);
DISPLAY 0.872340 (-5700 4275);
PAINT GREEN (-5700 4275);
DISPLAY INVISIBLE (-5700 4275);
FORCEPROP 1 LAST HDL_TAP TRUE
J 2
(-6025 4100);
DISPLAY 0.872340 (-6025 4100);
DISPLAY INVISIBLE (-6025 4100);
FORCEPROP 1 LAST PATH I286
J 2
(-5698 4225);
DISPLAY 0.872340 (-5698 4225);
PAINT GREEN (-5698 4225);
DISPLAY INVISIBLE (-5698 4225);
FORCEADD TAP..1
R 2
(-5700 4125);
FORCEPROP 3 LASTPIN (-5650 4125) SIG_NAME M_B_CPU0_SB_DQS_DP<7>
J 0
(-5640 4135);
DISPLAY 0.659574 (-5640 4135);
PAINT MONO (-5640 4135);
DISPLAY INVISIBLE (-5640 4135);
FORCEPROP 1 LASTPIN (-5650 4125) BN 7
J 2
(-5638 4133);
DISPLAY 0.489362 (-5638 4133);
PAINT GREEN (-5638 4133);
FORCEPROP 2 LAST CDS_LIB mstr_standard
J 2
(-5700 4125);
DISPLAY 0.723404 (-5700 4125);
PAINT MONO (-5700 4125);
DISPLAY INVISIBLE (-5700 4125);
FORCEPROP 1 LAST BODY_TYPE PLUMBING
J 2
(-5700 4175);
DISPLAY 0.872340 (-5700 4175);
PAINT GREEN (-5700 4175);
DISPLAY INVISIBLE (-5700 4175);
FORCEPROP 1 LAST HDL_TAP TRUE
J 2
(-6025 4000);
DISPLAY 0.872340 (-6025 4000);
DISPLAY INVISIBLE (-6025 4000);
FORCEPROP 1 LAST PATH I287
J 2
(-5698 4125);
DISPLAY 0.872340 (-5698 4125);
PAINT GREEN (-5698 4125);
DISPLAY INVISIBLE (-5698 4125);
FORCEADD TAP..1
R 2
(-5700 4325);
FORCEPROP 3 LASTPIN (-5650 4325) SIG_NAME M_B_CPU0_SB_DQS_DP<5>
J 0
(-5640 4335);
DISPLAY 0.659574 (-5640 4335);
PAINT MONO (-5640 4335);
DISPLAY INVISIBLE (-5640 4335);
FORCEPROP 1 LASTPIN (-5650 4325) BN 5
J 2
(-5638 4333);
DISPLAY 0.489362 (-5638 4333);
PAINT GREEN (-5638 4333);
FORCEPROP 2 LAST CDS_LIB mstr_standard
J 2
(-5700 4325);
DISPLAY 0.723404 (-5700 4325);
PAINT MONO (-5700 4325);
DISPLAY INVISIBLE (-5700 4325);
FORCEPROP 1 LAST BODY_TYPE PLUMBING
J 2
(-5700 4375);
DISPLAY 0.872340 (-5700 4375);
PAINT GREEN (-5700 4375);
DISPLAY INVISIBLE (-5700 4375);
FORCEPROP 1 LAST HDL_TAP TRUE
J 2
(-6025 4200);
DISPLAY 0.872340 (-6025 4200);
DISPLAY INVISIBLE (-6025 4200);
FORCEPROP 1 LAST PATH I288
J 2
(-5698 4325);
DISPLAY 0.872340 (-5698 4325);
PAINT GREEN (-5698 4325);
DISPLAY INVISIBLE (-5698 4325);
FORCEADD TAP..1
R 2
(-5900 4175);
FORCEPROP 3 LASTPIN (-5850 4175) SIG_NAME M_B_CPU0_SB_DQS_DN<6>
J 0
(-5840 4185);
DISPLAY 0.659574 (-5840 4185);
PAINT MONO (-5840 4185);
DISPLAY INVISIBLE (-5840 4185);
FORCEPROP 1 LASTPIN (-5850 4175) BN 6
J 2
(-5838 4183);
DISPLAY 0.489362 (-5838 4183);
PAINT GREEN (-5838 4183);
FORCEPROP 2 LAST CDS_LIB mstr_standard
J 2
(-5900 4175);
DISPLAY 0.723404 (-5900 4175);
PAINT MONO (-5900 4175);
DISPLAY INVISIBLE (-5900 4175);
FORCEPROP 1 LAST BODY_TYPE PLUMBING
J 2
(-5900 4225);
DISPLAY 0.872340 (-5900 4225);
PAINT GREEN (-5900 4225);
DISPLAY INVISIBLE (-5900 4225);
FORCEPROP 1 LAST HDL_TAP TRUE
J 2
(-6225 4050);
DISPLAY 0.872340 (-6225 4050);
DISPLAY INVISIBLE (-6225 4050);
FORCEPROP 1 LAST PATH I289
J 2
(-5898 4175);
DISPLAY 0.872340 (-5898 4175);
PAINT GREEN (-5898 4175);
DISPLAY INVISIBLE (-5898 4175);
FORCEADD TAP..1
R 2
(-5900 4275);
FORCEPROP 3 LASTPIN (-5850 4275) SIG_NAME M_B_CPU0_SB_DQS_DN<5>
J 0
(-5840 4285);
DISPLAY 0.659574 (-5840 4285);
PAINT MONO (-5840 4285);
DISPLAY INVISIBLE (-5840 4285);
FORCEPROP 1 LASTPIN (-5850 4275) BN 5
J 2
(-5838 4283);
DISPLAY 0.489362 (-5838 4283);
PAINT GREEN (-5838 4283);
FORCEPROP 2 LAST CDS_LIB mstr_standard
J 2
(-5900 4275);
DISPLAY 0.723404 (-5900 4275);
PAINT MONO (-5900 4275);
DISPLAY INVISIBLE (-5900 4275);
FORCEPROP 1 LAST BODY_TYPE PLUMBING
J 2
(-5900 4325);
DISPLAY 0.872340 (-5900 4325);
PAINT GREEN (-5900 4325);
DISPLAY INVISIBLE (-5900 4325);
FORCEPROP 1 LAST HDL_TAP TRUE
J 2
(-6225 4150);
DISPLAY 0.872340 (-6225 4150);
DISPLAY INVISIBLE (-6225 4150);
FORCEPROP 1 LAST PATH I290
J 2
(-5898 4275);
DISPLAY 0.872340 (-5898 4275);
PAINT GREEN (-5898 4275);
DISPLAY INVISIBLE (-5898 4275);
FORCEADD OFFPAGE..3
R 2
(-6600 5850);
FORCEPROP 2 LAST $XR0 87 
J 0
(-6879 5850);
DISPLAY 0.638298 (-6879 5850);
PAINT MONO (-6879 5850);
FORCEPROP 2 LAST CDS_LIB standard
J 0
(-6600 5850);
DISPLAY INVISIBLE (-6600 5850);
FORCEPROP 1 LAST OFFPAGE TRUE
J 2
(-6925 5725);
DISPLAY 0.872340 (-6925 5725);
PAINT GREEN (-6925 5725);
DISPLAY INVISIBLE (-6925 5725);
FORCEPROP 1 LAST COMMENT_BODY TRUE
J 2
(-6550 5750);
DISPLAY 0.872340 (-6550 5750);
PAINT GREEN (-6550 5750);
DISPLAY INVISIBLE (-6550 5750);
FORCEPROP 2 LAST PATH I291
J 0
(-6875 5900);
DISPLAY 1.021277 (-6875 5900);
DISPLAY INVISIBLE (-6875 5900);
FORCEADD OFFPAGE..3
R 2
(-6600 5900);
FORCEPROP 2 LAST $XR0 87 
J 0
(-6879 5900);
DISPLAY 0.638298 (-6879 5900);
PAINT MONO (-6879 5900);
FORCEPROP 2 LAST CDS_LIB standard
J 0
(-6600 5900);
DISPLAY INVISIBLE (-6600 5900);
FORCEPROP 1 LAST OFFPAGE TRUE
J 2
(-6925 5775);
DISPLAY 0.872340 (-6925 5775);
PAINT GREEN (-6925 5775);
DISPLAY INVISIBLE (-6925 5775);
FORCEPROP 1 LAST COMMENT_BODY TRUE
J 2
(-6550 5800);
DISPLAY 0.872340 (-6550 5800);
PAINT GREEN (-6550 5800);
DISPLAY INVISIBLE (-6550 5800);
FORCEPROP 2 LAST PATH I292
J 0
(-6875 5950);
DISPLAY 1.021277 (-6875 5950);
DISPLAY INVISIBLE (-6875 5950);
FORCEADD OFFPAGE..3
R 2
(-6600 4850);
FORCEPROP 2 LAST $XR0 87 
J 0
(-6879 4850);
DISPLAY 0.638298 (-6879 4850);
PAINT MONO (-6879 4850);
FORCEPROP 2 LAST CDS_LIB standard
J 0
(-6600 4850);
DISPLAY INVISIBLE (-6600 4850);
FORCEPROP 1 LAST OFFPAGE TRUE
J 2
(-6925 4725);
DISPLAY 0.872340 (-6925 4725);
PAINT GREEN (-6925 4725);
DISPLAY INVISIBLE (-6925 4725);
FORCEPROP 1 LAST COMMENT_BODY TRUE
J 2
(-6550 4750);
DISPLAY 0.872340 (-6550 4750);
PAINT GREEN (-6550 4750);
DISPLAY INVISIBLE (-6550 4750);
FORCEPROP 2 LAST PATH I293
J 0
(-6875 4900);
DISPLAY 1.021277 (-6875 4900);
DISPLAY INVISIBLE (-6875 4900);
FORCEADD OFFPAGE..3
R 2
(-6600 4800);
FORCEPROP 2 LAST $XR0 87 
J 0
(-6879 4800);
DISPLAY 0.638298 (-6879 4800);
PAINT MONO (-6879 4800);
FORCEPROP 2 LAST CDS_LIB standard
J 0
(-6600 4800);
DISPLAY INVISIBLE (-6600 4800);
FORCEPROP 1 LAST OFFPAGE TRUE
J 2
(-6925 4675);
DISPLAY 0.872340 (-6925 4675);
PAINT GREEN (-6925 4675);
DISPLAY INVISIBLE (-6925 4675);
FORCEPROP 1 LAST COMMENT_BODY TRUE
J 2
(-6550 4700);
DISPLAY 0.872340 (-6550 4700);
PAINT GREEN (-6550 4700);
DISPLAY INVISIBLE (-6550 4700);
FORCEPROP 2 LAST PATH I294
J 0
(-6875 4850);
DISPLAY 1.021277 (-6875 4850);
DISPLAY INVISIBLE (-6875 4850);
FORCEADD TAP..1
R 2
(-5700 4025);
FORCEPROP 3 LASTPIN (-5650 4025) SIG_NAME M_B_CPU0_SB_DQS_DP<8>
J 0
(-5640 4035);
DISPLAY 0.659574 (-5640 4035);
PAINT MONO (-5640 4035);
DISPLAY INVISIBLE (-5640 4035);
FORCEPROP 1 LASTPIN (-5650 4025) BN 8
J 2
(-5638 4033);
DISPLAY 0.489362 (-5638 4033);
PAINT GREEN (-5638 4033);
FORCEPROP 2 LAST CDS_LIB mstr_standard
J 2
(-5700 4025);
DISPLAY 0.723404 (-5700 4025);
PAINT MONO (-5700 4025);
DISPLAY INVISIBLE (-5700 4025);
FORCEPROP 1 LAST BODY_TYPE PLUMBING
J 2
(-5700 4075);
DISPLAY 0.872340 (-5700 4075);
PAINT GREEN (-5700 4075);
DISPLAY INVISIBLE (-5700 4075);
FORCEPROP 1 LAST HDL_TAP TRUE
J 2
(-6025 3900);
DISPLAY 0.872340 (-6025 3900);
DISPLAY INVISIBLE (-6025 3900);
FORCEPROP 1 LAST PATH I295
J 2
(-5698 4025);
DISPLAY 0.872340 (-5698 4025);
PAINT GREEN (-5698 4025);
DISPLAY INVISIBLE (-5698 4025);
FORCEADD TAP..1
R 2
(-5700 3925);
FORCEPROP 3 LASTPIN (-5650 3925) SIG_NAME M_B_CPU0_SB_DQS_DP<9>
J 0
(-5640 3935);
DISPLAY 0.659574 (-5640 3935);
PAINT MONO (-5640 3935);
DISPLAY INVISIBLE (-5640 3935);
FORCEPROP 1 LASTPIN (-5650 3925) BN 9
J 2
(-5638 3933);
DISPLAY 0.489362 (-5638 3933);
PAINT GREEN (-5638 3933);
FORCEPROP 2 LAST CDS_LIB mstr_standard
J 2
(-5700 3925);
DISPLAY 0.723404 (-5700 3925);
PAINT MONO (-5700 3925);
DISPLAY INVISIBLE (-5700 3925);
FORCEPROP 1 LAST BODY_TYPE PLUMBING
J 2
(-5700 3975);
DISPLAY 0.872340 (-5700 3975);
PAINT GREEN (-5700 3975);
DISPLAY INVISIBLE (-5700 3975);
FORCEPROP 1 LAST HDL_TAP TRUE
J 2
(-6025 3800);
DISPLAY 0.872340 (-6025 3800);
DISPLAY INVISIBLE (-6025 3800);
FORCEPROP 1 LAST PATH I296
J 2
(-5698 3925);
DISPLAY 0.872340 (-5698 3925);
PAINT GREEN (-5698 3925);
DISPLAY INVISIBLE (-5698 3925);
FORCEADD TAP..1
R 2
(-5900 3875);
FORCEPROP 3 LASTPIN (-5850 3875) SIG_NAME M_B_CPU0_SB_DQS_DN<9>
J 0
(-5840 3885);
DISPLAY 0.659574 (-5840 3885);
PAINT MONO (-5840 3885);
DISPLAY INVISIBLE (-5840 3885);
FORCEPROP 1 LASTPIN (-5850 3875) BN 9
J 2
(-5838 3883);
DISPLAY 0.489362 (-5838 3883);
PAINT GREEN (-5838 3883);
FORCEPROP 2 LAST CDS_LIB mstr_standard
J 2
(-5900 3875);
DISPLAY 0.723404 (-5900 3875);
PAINT MONO (-5900 3875);
DISPLAY INVISIBLE (-5900 3875);
FORCEPROP 1 LAST BODY_TYPE PLUMBING
J 2
(-5900 3925);
DISPLAY 0.872340 (-5900 3925);
PAINT GREEN (-5900 3925);
DISPLAY INVISIBLE (-5900 3925);
FORCEPROP 1 LAST HDL_TAP TRUE
J 2
(-6225 3750);
DISPLAY 0.872340 (-6225 3750);
DISPLAY INVISIBLE (-6225 3750);
FORCEPROP 1 LAST PATH I297
J 2
(-5898 3875);
DISPLAY 0.872340 (-5898 3875);
PAINT GREEN (-5898 3875);
DISPLAY INVISIBLE (-5898 3875);
FORCEADD TAP..1
R 2
(-5900 3975);
FORCEPROP 3 LASTPIN (-5850 3975) SIG_NAME M_B_CPU0_SB_DQS_DN<8>
J 0
(-5840 3985);
DISPLAY 0.659574 (-5840 3985);
PAINT MONO (-5840 3985);
DISPLAY INVISIBLE (-5840 3985);
FORCEPROP 1 LASTPIN (-5850 3975) BN 8
J 2
(-5838 3983);
DISPLAY 0.489362 (-5838 3983);
PAINT GREEN (-5838 3983);
FORCEPROP 2 LAST CDS_LIB mstr_standard
J 2
(-5900 3975);
DISPLAY 0.723404 (-5900 3975);
PAINT MONO (-5900 3975);
DISPLAY INVISIBLE (-5900 3975);
FORCEPROP 1 LAST BODY_TYPE PLUMBING
J 2
(-5900 4025);
DISPLAY 0.872340 (-5900 4025);
PAINT GREEN (-5900 4025);
DISPLAY INVISIBLE (-5900 4025);
FORCEPROP 1 LAST HDL_TAP TRUE
J 2
(-6225 3850);
DISPLAY 0.872340 (-6225 3850);
DISPLAY INVISIBLE (-6225 3850);
FORCEPROP 1 LAST PATH I298
J 2
(-5898 3975);
DISPLAY 0.872340 (-5898 3975);
PAINT GREEN (-5898 3975);
DISPLAY INVISIBLE (-5898 3975);
FORCEADD TAP..1
R 2
(-5900 4075);
FORCEPROP 3 LASTPIN (-5850 4075) SIG_NAME M_B_CPU0_SB_DQS_DN<7>
J 0
(-5840 4085);
DISPLAY 0.659574 (-5840 4085);
PAINT MONO (-5840 4085);
DISPLAY INVISIBLE (-5840 4085);
FORCEPROP 1 LASTPIN (-5850 4075) BN 7
J 2
(-5838 4083);
DISPLAY 0.489362 (-5838 4083);
PAINT GREEN (-5838 4083);
FORCEPROP 2 LAST CDS_LIB mstr_standard
J 2
(-5900 4075);
DISPLAY 0.723404 (-5900 4075);
PAINT MONO (-5900 4075);
DISPLAY INVISIBLE (-5900 4075);
FORCEPROP 1 LAST BODY_TYPE PLUMBING
J 2
(-5900 4125);
DISPLAY 0.872340 (-5900 4125);
PAINT GREEN (-5900 4125);
DISPLAY INVISIBLE (-5900 4125);
FORCEPROP 1 LAST HDL_TAP TRUE
J 2
(-6225 3950);
DISPLAY 0.872340 (-6225 3950);
DISPLAY INVISIBLE (-6225 3950);
FORCEPROP 1 LAST PATH I299
J 2
(-5898 4075);
DISPLAY 0.872340 (-5898 4075);
PAINT GREEN (-5898 4075);
DISPLAY INVISIBLE (-5898 4075);
FORCEADD TAP..1
R 2
(-5900 3725);
FORCEPROP 3 LASTPIN (-5850 3725) SIG_NAME M_B_CPU0_SA_CA<0>
J 0
(-5840 3735);
DISPLAY 0.659574 (-5840 3735);
PAINT MONO (-5840 3735);
DISPLAY INVISIBLE (-5840 3735);
FORCEPROP 1 LASTPIN (-5850 3725) BN 0
J 2
(-5838 3733);
DISPLAY 0.489362 (-5838 3733);
PAINT GREEN (-5838 3733);
FORCEPROP 2 LAST CDS_LIB mstr_standard
J 0
(-5900 3725);
DISPLAY 0.723404 (-5900 3725);
PAINT MONO (-5900 3725);
DISPLAY INVISIBLE (-5900 3725);
FORCEPROP 1 LAST BODY_TYPE PLUMBING
J 2
(-5900 3775);
DISPLAY 0.872340 (-5900 3775);
PAINT GREEN (-5900 3775);
DISPLAY INVISIBLE (-5900 3775);
FORCEPROP 1 LAST HDL_TAP TRUE
J 2
(-6225 3600);
DISPLAY 0.872340 (-6225 3600);
DISPLAY INVISIBLE (-6225 3600);
FORCEPROP 1 LAST PATH I300
J 2
(-5898 3725);
DISPLAY 0.872340 (-5898 3725);
PAINT GREEN (-5898 3725);
DISPLAY INVISIBLE (-5898 3725);
FORCEADD TAP..1
R 2
(-5900 3675);
FORCEPROP 3 LASTPIN (-5850 3675) SIG_NAME M_B_CPU0_SA_CA<1>
J 0
(-5840 3685);
DISPLAY 0.659574 (-5840 3685);
PAINT MONO (-5840 3685);
DISPLAY INVISIBLE (-5840 3685);
FORCEPROP 1 LASTPIN (-5850 3675) BN 1
J 2
(-5838 3683);
DISPLAY 0.489362 (-5838 3683);
PAINT GREEN (-5838 3683);
FORCEPROP 2 LAST CDS_LIB mstr_standard
J 0
(-5900 3675);
DISPLAY 0.723404 (-5900 3675);
PAINT MONO (-5900 3675);
DISPLAY INVISIBLE (-5900 3675);
FORCEPROP 1 LAST BODY_TYPE PLUMBING
J 2
(-5900 3725);
DISPLAY 0.872340 (-5900 3725);
PAINT GREEN (-5900 3725);
DISPLAY INVISIBLE (-5900 3725);
FORCEPROP 1 LAST HDL_TAP TRUE
J 2
(-6225 3550);
DISPLAY 0.872340 (-6225 3550);
DISPLAY INVISIBLE (-6225 3550);
FORCEPROP 1 LAST PATH I301
J 2
(-5898 3675);
DISPLAY 0.872340 (-5898 3675);
PAINT GREEN (-5898 3675);
DISPLAY INVISIBLE (-5898 3675);
FORCEADD TAP..1
R 2
(-5900 3625);
FORCEPROP 3 LASTPIN (-5850 3625) SIG_NAME M_B_CPU0_SA_CA<2>
J 0
(-5840 3635);
DISPLAY 0.659574 (-5840 3635);
PAINT MONO (-5840 3635);
DISPLAY INVISIBLE (-5840 3635);
FORCEPROP 1 LASTPIN (-5850 3625) BN 2
J 2
(-5838 3633);
DISPLAY 0.489362 (-5838 3633);
PAINT GREEN (-5838 3633);
FORCEPROP 2 LAST CDS_LIB mstr_standard
J 0
(-5900 3625);
DISPLAY 0.723404 (-5900 3625);
PAINT MONO (-5900 3625);
DISPLAY INVISIBLE (-5900 3625);
FORCEPROP 1 LAST BODY_TYPE PLUMBING
J 2
(-5900 3675);
DISPLAY 0.872340 (-5900 3675);
PAINT GREEN (-5900 3675);
DISPLAY INVISIBLE (-5900 3675);
FORCEPROP 1 LAST HDL_TAP TRUE
J 2
(-6225 3500);
DISPLAY 0.872340 (-6225 3500);
DISPLAY INVISIBLE (-6225 3500);
FORCEPROP 1 LAST PATH I302
J 2
(-5898 3625);
DISPLAY 0.872340 (-5898 3625);
PAINT GREEN (-5898 3625);
DISPLAY INVISIBLE (-5898 3625);
FORCEADD TAP..1
R 2
(-5900 3525);
FORCEPROP 3 LASTPIN (-5850 3525) SIG_NAME M_B_CPU0_SA_CA<4>
J 0
(-5840 3535);
DISPLAY 0.659574 (-5840 3535);
PAINT MONO (-5840 3535);
DISPLAY INVISIBLE (-5840 3535);
FORCEPROP 1 LASTPIN (-5850 3525) BN 4
J 2
(-5838 3533);
DISPLAY 0.489362 (-5838 3533);
PAINT GREEN (-5838 3533);
FORCEPROP 2 LAST CDS_LIB mstr_standard
J 0
(-5900 3525);
DISPLAY 0.723404 (-5900 3525);
PAINT MONO (-5900 3525);
DISPLAY INVISIBLE (-5900 3525);
FORCEPROP 1 LAST BODY_TYPE PLUMBING
J 2
(-5900 3575);
DISPLAY 0.872340 (-5900 3575);
PAINT GREEN (-5900 3575);
DISPLAY INVISIBLE (-5900 3575);
FORCEPROP 1 LAST HDL_TAP TRUE
J 2
(-6225 3400);
DISPLAY 0.872340 (-6225 3400);
DISPLAY INVISIBLE (-6225 3400);
FORCEPROP 1 LAST PATH I303
J 2
(-5898 3525);
DISPLAY 0.872340 (-5898 3525);
PAINT GREEN (-5898 3525);
DISPLAY INVISIBLE (-5898 3525);
FORCEADD TAP..1
R 2
(-5900 3475);
FORCEPROP 3 LASTPIN (-5850 3475) SIG_NAME M_B_CPU0_SA_CA<5>
J 0
(-5840 3485);
DISPLAY 0.659574 (-5840 3485);
PAINT MONO (-5840 3485);
DISPLAY INVISIBLE (-5840 3485);
FORCEPROP 1 LASTPIN (-5850 3475) BN 5
J 2
(-5838 3483);
DISPLAY 0.489362 (-5838 3483);
PAINT GREEN (-5838 3483);
FORCEPROP 2 LAST CDS_LIB mstr_standard
J 0
(-5900 3475);
DISPLAY 0.723404 (-5900 3475);
PAINT MONO (-5900 3475);
DISPLAY INVISIBLE (-5900 3475);
FORCEPROP 1 LAST BODY_TYPE PLUMBING
J 2
(-5900 3525);
DISPLAY 0.872340 (-5900 3525);
PAINT GREEN (-5900 3525);
DISPLAY INVISIBLE (-5900 3525);
FORCEPROP 1 LAST HDL_TAP TRUE
J 2
(-6225 3350);
DISPLAY 0.872340 (-6225 3350);
DISPLAY INVISIBLE (-6225 3350);
FORCEPROP 1 LAST PATH I304
J 2
(-5898 3475);
DISPLAY 0.872340 (-5898 3475);
PAINT GREEN (-5898 3475);
DISPLAY INVISIBLE (-5898 3475);
FORCEADD TAP..1
R 2
(-5900 3575);
FORCEPROP 3 LASTPIN (-5850 3575) SIG_NAME M_B_CPU0_SA_CA<3>
J 0
(-5840 3585);
DISPLAY 0.659574 (-5840 3585);
PAINT MONO (-5840 3585);
DISPLAY INVISIBLE (-5840 3585);
FORCEPROP 1 LASTPIN (-5850 3575) BN 3
J 2
(-5838 3583);
DISPLAY 0.489362 (-5838 3583);
PAINT GREEN (-5838 3583);
FORCEPROP 2 LAST CDS_LIB mstr_standard
J 0
(-5900 3575);
DISPLAY 0.723404 (-5900 3575);
PAINT MONO (-5900 3575);
DISPLAY INVISIBLE (-5900 3575);
FORCEPROP 1 LAST BODY_TYPE PLUMBING
J 2
(-5900 3625);
DISPLAY 0.872340 (-5900 3625);
PAINT GREEN (-5900 3625);
DISPLAY INVISIBLE (-5900 3625);
FORCEPROP 1 LAST HDL_TAP TRUE
J 2
(-6225 3450);
DISPLAY 0.872340 (-6225 3450);
DISPLAY INVISIBLE (-6225 3450);
FORCEPROP 1 LAST PATH I305
J 2
(-5898 3575);
DISPLAY 0.872340 (-5898 3575);
PAINT GREEN (-5898 3575);
DISPLAY INVISIBLE (-5898 3575);
FORCEADD TAP..1
R 2
(-5900 3425);
FORCEPROP 3 LASTPIN (-5850 3425) SIG_NAME M_B_CPU0_SA_CA<6>
J 0
(-5840 3435);
DISPLAY 0.659574 (-5840 3435);
PAINT MONO (-5840 3435);
DISPLAY INVISIBLE (-5840 3435);
FORCEPROP 1 LASTPIN (-5850 3425) BN 6
J 2
(-5838 3433);
DISPLAY 0.489362 (-5838 3433);
PAINT GREEN (-5838 3433);
FORCEPROP 2 LAST CDS_LIB mstr_standard
J 0
(-5900 3425);
DISPLAY 0.723404 (-5900 3425);
PAINT MONO (-5900 3425);
DISPLAY INVISIBLE (-5900 3425);
FORCEPROP 1 LAST BODY_TYPE PLUMBING
J 2
(-5900 3475);
DISPLAY 0.872340 (-5900 3475);
PAINT GREEN (-5900 3475);
DISPLAY INVISIBLE (-5900 3475);
FORCEPROP 1 LAST HDL_TAP TRUE
J 2
(-6225 3300);
DISPLAY 0.872340 (-6225 3300);
DISPLAY INVISIBLE (-6225 3300);
FORCEPROP 1 LAST PATH I306
J 2
(-5898 3425);
DISPLAY 0.872340 (-5898 3425);
PAINT GREEN (-5898 3425);
DISPLAY INVISIBLE (-5898 3425);
FORCEADD TAP..1
R 2
(-5900 3325);
FORCEPROP 3 LASTPIN (-5850 3325) SIG_NAME M_B_CPU0_SB_CA<0>
J 0
(-5840 3335);
DISPLAY 0.659574 (-5840 3335);
PAINT MONO (-5840 3335);
DISPLAY INVISIBLE (-5840 3335);
FORCEPROP 1 LASTPIN (-5850 3325) BN 0
J 2
(-5838 3333);
DISPLAY 0.489362 (-5838 3333);
PAINT GREEN (-5838 3333);
FORCEPROP 2 LAST CDS_LIB mstr_standard
J 0
(-5900 3325);
DISPLAY 0.723404 (-5900 3325);
PAINT MONO (-5900 3325);
DISPLAY INVISIBLE (-5900 3325);
FORCEPROP 1 LAST BODY_TYPE PLUMBING
J 2
(-5900 3375);
DISPLAY 0.872340 (-5900 3375);
PAINT GREEN (-5900 3375);
DISPLAY INVISIBLE (-5900 3375);
FORCEPROP 1 LAST HDL_TAP TRUE
J 2
(-6225 3200);
DISPLAY 0.872340 (-6225 3200);
DISPLAY INVISIBLE (-6225 3200);
FORCEPROP 1 LAST PATH I307
J 2
(-5898 3325);
DISPLAY 0.872340 (-5898 3325);
PAINT GREEN (-5898 3325);
DISPLAY INVISIBLE (-5898 3325);
FORCEADD TAP..1
R 2
(-5900 3275);
FORCEPROP 3 LASTPIN (-5850 3275) SIG_NAME M_B_CPU0_SB_CA<1>
J 0
(-5840 3285);
DISPLAY 0.659574 (-5840 3285);
PAINT MONO (-5840 3285);
DISPLAY INVISIBLE (-5840 3285);
FORCEPROP 1 LASTPIN (-5850 3275) BN 1
J 2
(-5838 3283);
DISPLAY 0.489362 (-5838 3283);
PAINT GREEN (-5838 3283);
FORCEPROP 2 LAST CDS_LIB mstr_standard
J 0
(-5900 3275);
DISPLAY 0.723404 (-5900 3275);
PAINT MONO (-5900 3275);
DISPLAY INVISIBLE (-5900 3275);
FORCEPROP 1 LAST BODY_TYPE PLUMBING
J 2
(-5900 3325);
DISPLAY 0.872340 (-5900 3325);
PAINT GREEN (-5900 3325);
DISPLAY INVISIBLE (-5900 3325);
FORCEPROP 1 LAST HDL_TAP TRUE
J 2
(-6225 3150);
DISPLAY 0.872340 (-6225 3150);
DISPLAY INVISIBLE (-6225 3150);
FORCEPROP 1 LAST PATH I308
J 2
(-5898 3275);
DISPLAY 0.872340 (-5898 3275);
PAINT GREEN (-5898 3275);
DISPLAY INVISIBLE (-5898 3275);
FORCEADD TAP..1
R 2
(-5900 3225);
FORCEPROP 3 LASTPIN (-5850 3225) SIG_NAME M_B_CPU0_SB_CA<2>
J 0
(-5840 3235);
DISPLAY 0.659574 (-5840 3235);
PAINT MONO (-5840 3235);
DISPLAY INVISIBLE (-5840 3235);
FORCEPROP 1 LASTPIN (-5850 3225) BN 2
J 2
(-5838 3233);
DISPLAY 0.489362 (-5838 3233);
PAINT GREEN (-5838 3233);
FORCEPROP 2 LAST CDS_LIB mstr_standard
J 0
(-5900 3225);
DISPLAY 0.723404 (-5900 3225);
PAINT MONO (-5900 3225);
DISPLAY INVISIBLE (-5900 3225);
FORCEPROP 1 LAST BODY_TYPE PLUMBING
J 2
(-5900 3275);
DISPLAY 0.872340 (-5900 3275);
PAINT GREEN (-5900 3275);
DISPLAY INVISIBLE (-5900 3275);
FORCEPROP 1 LAST HDL_TAP TRUE
J 2
(-6225 3100);
DISPLAY 0.872340 (-6225 3100);
DISPLAY INVISIBLE (-6225 3100);
FORCEPROP 1 LAST PATH I309
J 2
(-5898 3225);
DISPLAY 0.872340 (-5898 3225);
PAINT GREEN (-5898 3225);
DISPLAY INVISIBLE (-5898 3225);
FORCEADD TAP..1
R 2
(-5900 3175);
FORCEPROP 3 LASTPIN (-5850 3175) SIG_NAME M_B_CPU0_SB_CA<3>
J 0
(-5840 3185);
DISPLAY 0.659574 (-5840 3185);
PAINT MONO (-5840 3185);
DISPLAY INVISIBLE (-5840 3185);
FORCEPROP 1 LASTPIN (-5850 3175) BN 3
J 2
(-5838 3183);
DISPLAY 0.489362 (-5838 3183);
PAINT GREEN (-5838 3183);
FORCEPROP 2 LAST CDS_LIB mstr_standard
J 0
(-5900 3175);
DISPLAY 0.723404 (-5900 3175);
PAINT MONO (-5900 3175);
DISPLAY INVISIBLE (-5900 3175);
FORCEPROP 1 LAST BODY_TYPE PLUMBING
J 2
(-5900 3225);
DISPLAY 0.872340 (-5900 3225);
PAINT GREEN (-5900 3225);
DISPLAY INVISIBLE (-5900 3225);
FORCEPROP 1 LAST HDL_TAP TRUE
J 2
(-6225 3050);
DISPLAY 0.872340 (-6225 3050);
DISPLAY INVISIBLE (-6225 3050);
FORCEPROP 1 LAST PATH I310
J 2
(-5898 3175);
DISPLAY 0.872340 (-5898 3175);
PAINT GREEN (-5898 3175);
DISPLAY INVISIBLE (-5898 3175);
FORCEADD TAP..1
R 2
(-5900 3125);
FORCEPROP 3 LASTPIN (-5850 3125) SIG_NAME M_B_CPU0_SB_CA<4>
J 0
(-5840 3135);
DISPLAY 0.659574 (-5840 3135);
PAINT MONO (-5840 3135);
DISPLAY INVISIBLE (-5840 3135);
FORCEPROP 1 LASTPIN (-5850 3125) BN 4
J 2
(-5838 3133);
DISPLAY 0.489362 (-5838 3133);
PAINT GREEN (-5838 3133);
FORCEPROP 2 LAST CDS_LIB mstr_standard
J 0
(-5900 3125);
DISPLAY 0.723404 (-5900 3125);
PAINT MONO (-5900 3125);
DISPLAY INVISIBLE (-5900 3125);
FORCEPROP 1 LAST BODY_TYPE PLUMBING
J 2
(-5900 3175);
DISPLAY 0.872340 (-5900 3175);
PAINT GREEN (-5900 3175);
DISPLAY INVISIBLE (-5900 3175);
FORCEPROP 1 LAST HDL_TAP TRUE
J 2
(-6225 3000);
DISPLAY 0.872340 (-6225 3000);
DISPLAY INVISIBLE (-6225 3000);
FORCEPROP 1 LAST PATH I311
J 2
(-5898 3125);
DISPLAY 0.872340 (-5898 3125);
PAINT GREEN (-5898 3125);
DISPLAY INVISIBLE (-5898 3125);
FORCEADD TAP..1
R 2
(-5900 3075);
FORCEPROP 3 LASTPIN (-5850 3075) SIG_NAME M_B_CPU0_SB_CA<5>
J 0
(-5840 3085);
DISPLAY 0.659574 (-5840 3085);
PAINT MONO (-5840 3085);
DISPLAY INVISIBLE (-5840 3085);
FORCEPROP 1 LASTPIN (-5850 3075) BN 5
J 2
(-5838 3083);
DISPLAY 0.489362 (-5838 3083);
PAINT GREEN (-5838 3083);
FORCEPROP 2 LAST CDS_LIB mstr_standard
J 0
(-5900 3075);
DISPLAY 0.723404 (-5900 3075);
PAINT MONO (-5900 3075);
DISPLAY INVISIBLE (-5900 3075);
FORCEPROP 1 LAST BODY_TYPE PLUMBING
J 2
(-5900 3125);
DISPLAY 0.872340 (-5900 3125);
PAINT GREEN (-5900 3125);
DISPLAY INVISIBLE (-5900 3125);
FORCEPROP 1 LAST HDL_TAP TRUE
J 2
(-6225 2950);
DISPLAY 0.872340 (-6225 2950);
DISPLAY INVISIBLE (-6225 2950);
FORCEPROP 1 LAST PATH I312
J 2
(-5898 3075);
DISPLAY 0.872340 (-5898 3075);
PAINT GREEN (-5898 3075);
DISPLAY INVISIBLE (-5898 3075);
FORCEADD TAP..1
R 2
(-5900 3025);
FORCEPROP 3 LASTPIN (-5850 3025) SIG_NAME M_B_CPU0_SB_CA<6>
J 0
(-5840 3035);
DISPLAY 0.659574 (-5840 3035);
PAINT MONO (-5840 3035);
DISPLAY INVISIBLE (-5840 3035);
FORCEPROP 1 LASTPIN (-5850 3025) BN 6
J 2
(-5838 3033);
DISPLAY 0.489362 (-5838 3033);
PAINT GREEN (-5838 3033);
FORCEPROP 2 LAST CDS_LIB mstr_standard
J 0
(-5900 3025);
DISPLAY 0.723404 (-5900 3025);
PAINT MONO (-5900 3025);
DISPLAY INVISIBLE (-5900 3025);
FORCEPROP 1 LAST BODY_TYPE PLUMBING
J 2
(-5900 3075);
DISPLAY 0.872340 (-5900 3075);
PAINT GREEN (-5900 3075);
DISPLAY INVISIBLE (-5900 3075);
FORCEPROP 1 LAST HDL_TAP TRUE
J 2
(-6225 2900);
DISPLAY 0.872340 (-6225 2900);
DISPLAY INVISIBLE (-6225 2900);
FORCEPROP 1 LAST PATH I313
J 2
(-5898 3025);
DISPLAY 0.872340 (-5898 3025);
PAINT GREEN (-5898 3025);
DISPLAY INVISIBLE (-5898 3025);
FORCEADD OFFPAGE..2
R 2
(-6500 3750);
FORCEPROP 2 LAST $XR0 87 
J 0
(-6754 3750);
DISPLAY 0.638298 (-6754 3750);
PAINT MONO (-6754 3750);
FORCEPROP 2 LAST CDS_LIB standard
J 0
(-6500 3750);
DISPLAY INVISIBLE (-6500 3750);
FORCEPROP 1 LAST OFFPAGE TRUE
J 2
(-6825 3625);
DISPLAY 0.872340 (-6825 3625);
PAINT GREEN (-6825 3625);
DISPLAY INVISIBLE (-6825 3625);
FORCEPROP 1 LAST COMMENT_BODY TRUE
J 2
(-6455 3655);
DISPLAY 0.872340 (-6455 3655);
PAINT GREEN (-6455 3655);
DISPLAY INVISIBLE (-6455 3655);
FORCEPROP 2 LAST PATH I314
J 0
(-6775 3800);
DISPLAY 1.021277 (-6775 3800);
DISPLAY INVISIBLE (-6775 3800);
FORCEADD OFFPAGE..2
R 2
(-6500 3350);
FORCEPROP 2 LAST $XR0 87 
J 0
(-6754 3350);
DISPLAY 0.638298 (-6754 3350);
PAINT MONO (-6754 3350);
FORCEPROP 2 LAST CDS_LIB standard
J 0
(-6500 3350);
DISPLAY INVISIBLE (-6500 3350);
FORCEPROP 1 LAST OFFPAGE TRUE
J 2
(-6825 3225);
DISPLAY 0.872340 (-6825 3225);
PAINT GREEN (-6825 3225);
DISPLAY INVISIBLE (-6825 3225);
FORCEPROP 1 LAST COMMENT_BODY TRUE
J 2
(-6455 3255);
DISPLAY 0.872340 (-6455 3255);
PAINT GREEN (-6455 3255);
DISPLAY INVISIBLE (-6455 3255);
FORCEPROP 2 LAST PATH I315
J 0
(-6775 3400);
DISPLAY 1.021277 (-6775 3400);
DISPLAY INVISIBLE (-6775 3400);
FORCEADD OFFPAGE..2
R 2
(-6500 2875);
FORCEPROP 2 LAST $XR0 87 
J 0
(-6754 2875);
DISPLAY 0.638298 (-6754 2875);
PAINT MONO (-6754 2875);
FORCEPROP 2 LAST CDS_LIB standard
J 0
(-6500 2875);
DISPLAY INVISIBLE (-6500 2875);
FORCEPROP 1 LAST OFFPAGE TRUE
J 2
(-6825 2750);
DISPLAY 0.872340 (-6825 2750);
PAINT GREEN (-6825 2750);
DISPLAY INVISIBLE (-6825 2750);
FORCEPROP 1 LAST COMMENT_BODY TRUE
J 2
(-6455 2780);
DISPLAY 0.872340 (-6455 2780);
PAINT GREEN (-6455 2780);
DISPLAY INVISIBLE (-6455 2780);
FORCEPROP 2 LAST PATH I316
J 0
(-6775 2925);
DISPLAY 1.021277 (-6775 2925);
DISPLAY INVISIBLE (-6775 2925);
FORCEADD OFFPAGE..2
R 2
(-6500 2825);
FORCEPROP 2 LAST $XR0 87 
J 0
(-6754 2825);
DISPLAY 0.638298 (-6754 2825);
PAINT MONO (-6754 2825);
FORCEPROP 2 LAST CDS_LIB standard
J 0
(-6500 2825);
DISPLAY INVISIBLE (-6500 2825);
FORCEPROP 1 LAST OFFPAGE TRUE
J 2
(-6825 2700);
DISPLAY 0.872340 (-6825 2700);
PAINT GREEN (-6825 2700);
DISPLAY INVISIBLE (-6825 2700);
FORCEPROP 1 LAST COMMENT_BODY TRUE
J 2
(-6455 2730);
DISPLAY 0.872340 (-6455 2730);
PAINT GREEN (-6455 2730);
DISPLAY INVISIBLE (-6455 2730);
FORCEPROP 2 LAST PATH I317
J 0
(-6775 2875);
DISPLAY 1.021277 (-6775 2875);
DISPLAY INVISIBLE (-6775 2875);
FORCEADD OFFPAGE..2
R 2
(-6500 2725);
FORCEPROP 2 LAST $XR0 87 
J 0
(-6754 2725);
DISPLAY 0.638298 (-6754 2725);
PAINT MONO (-6754 2725);
FORCEPROP 2 LAST CDS_LIB standard
J 0
(-6500 2725);
DISPLAY INVISIBLE (-6500 2725);
FORCEPROP 1 LAST OFFPAGE TRUE
J 2
(-6825 2600);
DISPLAY 0.872340 (-6825 2600);
PAINT GREEN (-6825 2600);
DISPLAY INVISIBLE (-6825 2600);
FORCEPROP 1 LAST COMMENT_BODY TRUE
J 2
(-6455 2630);
DISPLAY 0.872340 (-6455 2630);
PAINT GREEN (-6455 2630);
DISPLAY INVISIBLE (-6455 2630);
FORCEPROP 2 LAST PATH I318
J 0
(-6775 2775);
DISPLAY 1.021277 (-6775 2775);
DISPLAY INVISIBLE (-6775 2775);
FORCEADD OFFPAGE..2
R 2
(-6500 2675);
FORCEPROP 2 LAST $XR0 87 
J 0
(-6754 2675);
DISPLAY 0.638298 (-6754 2675);
PAINT MONO (-6754 2675);
FORCEPROP 2 LAST CDS_LIB standard
J 0
(-6500 2675);
DISPLAY INVISIBLE (-6500 2675);
FORCEPROP 1 LAST OFFPAGE TRUE
J 2
(-6825 2550);
DISPLAY 0.872340 (-6825 2550);
PAINT GREEN (-6825 2550);
DISPLAY INVISIBLE (-6825 2550);
FORCEPROP 1 LAST COMMENT_BODY TRUE
J 2
(-6455 2580);
DISPLAY 0.872340 (-6455 2580);
PAINT GREEN (-6455 2580);
DISPLAY INVISIBLE (-6455 2580);
FORCEPROP 2 LAST PATH I319
J 0
(-6775 2725);
DISPLAY 1.021277 (-6775 2725);
DISPLAY INVISIBLE (-6775 2725);
FORCEADD OFFPAGE..5
(-6500 2475);
FORCEPROP 2 LAST $XR0 87 
J 0
(-6754 2475);
DISPLAY 0.638298 (-6754 2475);
PAINT MONO (-6754 2475);
FORCEPROP 2 LAST CDS_LIB mstr_standard
J 0
(-6500 2475);
DISPLAY INVISIBLE (-6500 2475);
FORCEPROP 1 LAST OFFPAGE TRUE
J 0
(-6175 2350);
DISPLAY 0.872340 (-6175 2350);
PAINT GREEN (-6175 2350);
DISPLAY INVISIBLE (-6175 2350);
FORCEPROP 1 LAST COMMENT_BODY TRUE
J 0
(-6400 2400);
DISPLAY 0.872340 (-6400 2400);
PAINT GREEN (-6400 2400);
DISPLAY INVISIBLE (-6400 2400);
FORCEPROP 2 LAST PATH I320
J 0
(-6775 2525);
DISPLAY 1.021277 (-6775 2525);
DISPLAY INVISIBLE (-6775 2525);
FORCEADD OFFPAGE..2
R 2
(-6500 2375);
FORCEPROP 2 LAST $XR0 87 
J 0
(-6754 2375);
DISPLAY 0.638298 (-6754 2375);
PAINT MONO (-6754 2375);
FORCEPROP 2 LAST CDS_LIB standard
J 0
(-6500 2375);
DISPLAY INVISIBLE (-6500 2375);
FORCEPROP 1 LAST OFFPAGE TRUE
J 2
(-6825 2250);
DISPLAY 0.872340 (-6825 2250);
PAINT GREEN (-6825 2250);
DISPLAY INVISIBLE (-6825 2250);
FORCEPROP 1 LAST COMMENT_BODY TRUE
J 2
(-6455 2280);
DISPLAY 0.872340 (-6455 2280);
PAINT GREEN (-6455 2280);
DISPLAY INVISIBLE (-6455 2280);
FORCEPROP 2 LAST PATH I321
J 0
(-6775 2425);
DISPLAY 1.021277 (-6775 2425);
DISPLAY INVISIBLE (-6775 2425);
FORCEADD OFFPAGE..1
(-6500 2575);
FORCEPROP 2 LAST $XR0 87 
J 0
(-6721 2575);
DISPLAY 0.638298 (-6721 2575);
PAINT MONO (-6721 2575);
FORCEPROP 2 LAST CDS_LIB standard
J 0
(-6500 2575);
DISPLAY INVISIBLE (-6500 2575);
FORCEPROP 1 LAST OFFPAGE TRUE
J 0
(-6175 2450);
DISPLAY 0.872340 (-6175 2450);
PAINT GREEN (-6175 2450);
DISPLAY INVISIBLE (-6175 2450);
FORCEPROP 1 LAST COMMENT_BODY TRUE
J 0
(-6375 2475);
DISPLAY 0.872340 (-6375 2475);
PAINT GREEN (-6375 2475);
DISPLAY INVISIBLE (-6375 2475);
FORCEPROP 2 LAST PATH I322
J 0
(-6750 2625);
DISPLAY 1.021277 (-6750 2625);
DISPLAY INVISIBLE (-6750 2625);
FORCEADD OFFPAGE..2
R 2
(-6500 2325);
FORCEPROP 2 LAST $XR0 87 
J 0
(-6754 2325);
DISPLAY 0.638298 (-6754 2325);
PAINT MONO (-6754 2325);
FORCEPROP 2 LAST CDS_LIB standard
J 0
(-6500 2325);
DISPLAY INVISIBLE (-6500 2325);
FORCEPROP 1 LAST OFFPAGE TRUE
J 2
(-6825 2200);
DISPLAY 0.872340 (-6825 2200);
PAINT GREEN (-6825 2200);
DISPLAY INVISIBLE (-6825 2200);
FORCEPROP 1 LAST COMMENT_BODY TRUE
J 2
(-6455 2230);
DISPLAY 0.872340 (-6455 2230);
PAINT GREEN (-6455 2230);
DISPLAY INVISIBLE (-6455 2230);
FORCEPROP 2 LAST PATH I323
J 0
(-6775 2375);
DISPLAY 1.021277 (-6775 2375);
DISPLAY INVISIBLE (-6775 2375);
FORCEADD OFFPAGE..5
(-6500 2125);
FORCEPROP 2 LAST $XR0 87 
J 0
(-6754 2125);
DISPLAY 0.638298 (-6754 2125);
PAINT MONO (-6754 2125);
FORCEPROP 2 LAST CDS_LIB standard
J 0
(-6500 2125);
DISPLAY INVISIBLE (-6500 2125);
FORCEPROP 1 LAST OFFPAGE TRUE
J 0
(-6175 2000);
DISPLAY 0.872340 (-6175 2000);
PAINT GREEN (-6175 2000);
DISPLAY INVISIBLE (-6175 2000);
FORCEPROP 1 LAST COMMENT_BODY TRUE
J 0
(-6400 2050);
DISPLAY 0.872340 (-6400 2050);
PAINT GREEN (-6400 2050);
DISPLAY INVISIBLE (-6400 2050);
FORCEPROP 2 LAST PATH I324
J 0
(-6775 2175);
DISPLAY 1.021277 (-6775 2175);
DISPLAY INVISIBLE (-6775 2175);
FORCEADD OFFPAGE..1
(-6500 2225);
FORCEPROP 2 LAST $XR0 87 
J 0
(-6721 2225);
DISPLAY 0.638298 (-6721 2225);
PAINT MONO (-6721 2225);
FORCEPROP 2 LAST CDS_LIB standard
J 0
(-6500 2225);
DISPLAY INVISIBLE (-6500 2225);
FORCEPROP 1 LAST OFFPAGE TRUE
J 0
(-6175 2100);
DISPLAY 0.872340 (-6175 2100);
PAINT GREEN (-6175 2100);
DISPLAY INVISIBLE (-6175 2100);
FORCEPROP 1 LAST COMMENT_BODY TRUE
J 0
(-6375 2125);
DISPLAY 0.872340 (-6375 2125);
PAINT GREEN (-6375 2125);
DISPLAY INVISIBLE (-6375 2125);
FORCEPROP 2 LAST PATH I325
J 0
(-6750 2275);
DISPLAY 1.021277 (-6750 2275);
DISPLAY INVISIBLE (-6750 2275);
FORCEADD OFFPAGE..5
(-6500 1925);
FORCEPROP 2 LAST $XR0 87 
J 0
(-6754 1925);
DISPLAY 0.638298 (-6754 1925);
PAINT MONO (-6754 1925);
FORCEPROP 2 LAST CDS_LIB standard
J 0
(-6500 1925);
DISPLAY INVISIBLE (-6500 1925);
FORCEPROP 1 LAST OFFPAGE TRUE
J 0
(-6175 1800);
DISPLAY 0.872340 (-6175 1800);
PAINT GREEN (-6175 1800);
DISPLAY INVISIBLE (-6175 1800);
FORCEPROP 1 LAST COMMENT_BODY TRUE
J 0
(-6400 1850);
DISPLAY 0.872340 (-6400 1850);
PAINT GREEN (-6400 1850);
DISPLAY INVISIBLE (-6400 1850);
FORCEPROP 2 LAST PATH I326
J 0
(-6775 1975);
DISPLAY 1.021277 (-6775 1975);
DISPLAY INVISIBLE (-6775 1975);
FORCEADD Q_RES..1
(-6825 2025);
FORCEPROP 1 LAST LOCATION R376
J 0
(-7100 2025);
DISPLAY 0.489362 (-7100 2025);
PAINT SKYBLUE (-7100 2025);
FORCEPROP 0 LAST $SEC 1
J 0
(-7000 2075);
DISPLAY 0.680851 (-7000 2075);
PAINT MONO (-7000 2075);
DISPLAY INVISIBLE (-7000 2075);
FORCEPROP 0 LAST CDS_SEC 1
J 0
(-7000 2075);
DISPLAY 1.021277 (-7000 2075);
DISPLAY INVISIBLE (-7000 2075);
FORCEPROP 1 LASTPIN (-6925 2025) $PN 1
J 0
(-6913 2037);
DISPLAY 0.489362 (-6913 2037);
PAINT MONO (-6913 2037);
FORCEPROP 1 LASTPIN (-6725 2025) $PN 2
J 0
(-6763 2037);
DISPLAY 0.489362 (-6763 2037);
PAINT MONO (-6763 2037);
FORCEPROP 1 LAST PACK_TYPE 0402LF
J 0
(-7075 2000);
DISPLAY 0.489362 (-7075 2000);
PAINT SKYBLUE (-7075 2000);
FORCEPROP 1 LAST TOLERANCE 1%
J 0
(-6550 2025);
DISPLAY 0.489362 (-6550 2025);
PAINT SKYBLUE (-6550 2025);
FORCEPROP 1 LAST VALUE 15
J 2
(-6500 2025);
DISPLAY 0.489362 (-6500 2025);
PAINT SKYBLUE (-6500 2025);
FORCEPROP 1 LAST MATERIAL CHIP
J 0
(-6950 2150);
DISPLAY 0.638298 (-6950 2150);
PAINT SKYBLUE (-6950 2150);
DISPLAY INVISIBLE (-6950 2150);
FORCEPROP 1 LAST WATTAGE 1/16W
J 2
(-6600 2150);
DISPLAY 0.638298 (-6600 2150);
PAINT SKYBLUE (-6600 2150);
DISPLAY INVISIBLE (-6600 2150);
FORCEPROP 2 LAST CDS_LIB pure_quanta
J 0
(-6825 2025);
DISPLAY INVISIBLE (-6825 2025);
FORCEPROP 1 LAST PATH I327
J 0
(-6875 2175);
DISPLAY 0.978723 (-6875 2175);
PAINT WHITE (-6875 2175);
DISPLAY INVISIBLE (-6875 2175);
FORCEPROP 1 LAST PART_NUMBER CS01502FB03
J 0
(-6700 2000);
DISPLAY 0.489362 (-6700 2000);
PAINT SKYBLUE (-6700 2000);
DISPLAY INVISIBLE (-6700 2000);
FORCEADD OFFPAGE..1
(-7700 2025);
FORCEPROP 2 LAST $XR0 87 
J 0
(-7951 2025);
DISPLAY 0.638298 (-7951 2025);
PAINT MONO (-7951 2025);
FORCEPROP 2 LAST CDS_LIB mstr_standard
J 0
(-7700 2025);
DISPLAY INVISIBLE (-7700 2025);
FORCEPROP 1 LAST OFFPAGE TRUE
J 0
(-7375 1900);
DISPLAY 0.872340 (-7375 1900);
PAINT GREEN (-7375 1900);
DISPLAY INVISIBLE (-7375 1900);
FORCEPROP 1 LAST COMMENT_BODY TRUE
J 0
(-7575 1925);
DISPLAY 0.872340 (-7575 1925);
PAINT GREEN (-7575 1925);
DISPLAY INVISIBLE (-7575 1925);
FORCEPROP 2 LAST PATH I328
J 0
(-7975 2075);
DISPLAY 1.021277 (-7975 2075);
DISPLAY INVISIBLE (-7975 2075);
FORCEADD CAD_NOTE..1
(-7575 2325);
FORCEPROP 0 LAST L1 R1946 PLACE CLOSE TO CPU < 25MM
J 0
(-7725 2200);
DISPLAY 0.617021 (-7725 2200);
PAINT WHITE (-7725 2200);
FORCEPROP 2 LAST CDS_LIB pure_quanta_power
J 0
(-7575 2325);
DISPLAY INVISIBLE (-7575 2325);
FORCEPROP 1 LAST COMMENT_BODY TRUE
J 0
(-7550 2425);
DISPLAY 0.574468 (-7550 2425);
PAINT WHITE (-7550 2425);
DISPLAY INVISIBLE (-7550 2425);
FORCEADD QUANTA_TITLE_BLOCK_C..1
(0 0);
FORCEPROP 0 LAST CDS_CON_LAST_MODIFIED Thu Sep 14 16:11:48 2023
J 0
(-1885 15);
DISPLAY INVISIBLE (-1885 15);
FORCEPROP 1 LAST CUSTOM_TXT_CDS <CON_LAST_MODIFIED>
J 0
(-1885 15);
DISPLAY 0.978723 (-1885 15);
FORCEPROP 2 LAST CUSTOM_TXT_CDS <XR_PAGE_TITLE>
J 0
(-7890 5250);
DISPLAY 0.638298 (-7890 5250);
PAINT PINK (-7890 5250);
DISPLAY INVISIBLE (-7890 5250);
FORCEPROP 1 LAST CUSTOM_TXT_CDS <NAME_2>
J 0
(-3175 50);
FORCEPROP 1 LAST CUSTOM_TXT_CDS <NAME_1>
J 0
(-3175 175);
FORCEPROP 1 LAST CUSTOM_TXT_CDS <Q_NUMBER>
J 0
(-1403 103);
DISPLAY 1.212766 (-1403 103);
FORCEPROP 1 LAST CUSTOM_TXT_CDS <Q_PROJ>
J 0
(-2382 102);
DISPLAY 1.212766 (-2382 102);
FORCEPROP 1 LAST CUSTOM_TXT_CDS <Q_REV>
J 0
(-184 103);
DISPLAY 1.212766 (-184 103);
FORCEPROP 1 LAST CUSTOM_TXT_CDS <CON_PAGE_NUM> OF <CON_TOTAL_PAGES>
J 0
(-446 18);
DISPLAY 0.978723 (-446 18);
FORCEPROP 1 LAST Q_TITLE CPU0 DDR CHB
J 0
(-9300 50);
DISPLAY 2.446809 (-9300 50);
PAINT GREEN (-9300 50);
FORCEPROP 2 LAST CDS_LIB pure_quanta
J 0
(0 0);
DISPLAY INVISIBLE (0 0);
FORCEPROP 1 LAST CDS_LMAN_SYM_OUTLINE -9475,6775,100,-125
J 0
(0 0);
DISPLAY 0.468085 (0 0);
PAINT GREEN (0 0);
DISPLAY INVISIBLE (0 0);
FORCEPROP 2 LAST PAGE_BORDER TRUE
J 0
(-7890 5250);
DISPLAY 0.638298 (-7890 5250);
PAINT PINK (-7890 5250);
DISPLAY INVISIBLE (-7890 5250);
FORCEPROP 2 LAST CDS_XR_PAGE_TITLE CR-11 : @T6G_MB_LIB.T6G(SCH_1):PAGE11
J 0
(-7890 5250);
DISPLAY 0.638298 (-7890 5250);
PAINT PINK (-7890 5250);
DISPLAY INVISIBLE (-7890 5250);
FORCEPROP 1 LAST Q_DEPT BU9
J 1
(-3763 49);
DISPLAY 1.957447 (-3763 49);
PAINT GREEN (-3763 49);
DISPLAY INVISIBLE (-3763 49);
FORCEPROP 1 LAST COMMENT_BODY TRUE
J 0
(12 -13);
DISPLAY 0.978723 (12 -13);
PAINT GREEN (12 -13);
DISPLAY INVISIBLE (12 -13);
WIRE 17 -1 (-5950 3050)(-5950 3100);
WIRE 17 -1 (-5950 3100)(-5950 3150);
WIRE 17 -1 (-5950 3150)(-5950 3200);
WIRE 17 -1 (-5950 3200)(-5950 3250);
WIRE 17 -1 (-5950 3250)(-5950 3300);
WIRE 17 -1 (-5950 3300)(-5950 3350);
WIRE 17 -1 (-5950 3350)(-6450 3350);
FORCEPROP 2 LAST SIG_NAME M_B_CPU0_SB_CA<6:0>
J 0
(-6450 3360);
DISPLAY 0.489362 (-6450 3360);
WIRE 17 -1 (-5750 4050)(-5750 3950);
WIRE 17 -1 (-5750 4150)(-5750 4050);
WIRE 17 -1 (-5750 4150)(-5750 4250);
WIRE 17 -1 (-5750 4250)(-5750 4350);
WIRE 17 -1 (-5750 4350)(-5750 4450);
WIRE 17 -1 (-5750 4550)(-5750 4450);
WIRE 17 -1 (-5750 4650)(-5750 4550);
WIRE 17 -1 (-5750 4750)(-5750 4650);
WIRE 17 -1 (-5750 4850)(-5750 4750);
WIRE 17 -1 (-5750 4850)(-6550 4850);
FORCEPROP 2 LAST SIG_NAME M_B_CPU0_SB_DQS_DP<9:0>
J 2
(-5985 4860);
DISPLAY 0.489362 (-5985 4860);
WIRE 17 -1 (-5950 4100)(-5950 4000);
WIRE 17 -1 (-5950 4100)(-5950 4200);
WIRE 17 -1 (-5950 4000)(-5950 3900);
WIRE 17 -1 (-5950 4200)(-5950 4300);
WIRE 17 -1 (-5950 4300)(-5950 4400);
WIRE 17 -1 (-5950 4500)(-5950 4400);
WIRE 17 -1 (-5950 4600)(-5950 4500);
WIRE 17 -1 (-5950 4700)(-5950 4600);
WIRE 17 -1 (-5950 4800)(-5950 4700);
FORCEPROP 2 LAST SIG_NAME M_B_CPU0_SB_DQS_DN<9:0>
J 2
(-5985 4810);
DISPLAY 0.489362 (-5985 4810);
WIRE 17 -1 (-5950 3450)(-5950 3500);
WIRE 17 -1 (-5950 3500)(-5950 3550);
WIRE 17 -1 (-5950 3550)(-5950 3600);
WIRE 17 -1 (-5950 3600)(-5950 3650);
WIRE 17 -1 (-5950 3650)(-5950 3700);
WIRE 17 -1 (-5950 3700)(-5950 3750);
WIRE 17 -1 (-5950 3750)(-6450 3750);
FORCEPROP 2 LAST SIG_NAME M_B_CPU0_SA_CA<6:0>
J 0
(-6450 3760);
DISPLAY 0.489362 (-6450 3760);
WIRE 17 -1 (-5750 5100)(-5750 5000);
WIRE 17 -1 (-5750 5200)(-5750 5100);
WIRE 17 -1 (-5750 5200)(-5750 5300);
WIRE 17 -1 (-5750 5300)(-5750 5400);
WIRE 17 -1 (-5750 5400)(-5750 5500);
WIRE 17 -1 (-5750 5600)(-5750 5500);
WIRE 17 -1 (-5750 5700)(-5750 5600);
WIRE 17 -1 (-5750 5800)(-5750 5700);
WIRE 17 -1 (-5750 5900)(-5750 5800);
WIRE 17 -1 (-5750 5900)(-6550 5900);
FORCEPROP 2 LAST SIG_NAME M_B_CPU0_SA_DQS_DP<9:0>
J 2
(-5985 5910);
DISPLAY 0.489362 (-5985 5910);
WIRE 17 -1 (-5950 5050)(-5950 4950);
WIRE 17 -1 (-5950 5150)(-5950 5050);
WIRE 17 -1 (-5950 5150)(-5950 5250);
WIRE 17 -1 (-5950 5250)(-5950 5350);
WIRE 17 -1 (-5950 5350)(-5950 5450);
WIRE 17 -1 (-5950 5550)(-5950 5450);
WIRE 17 -1 (-5950 5650)(-5950 5550);
WIRE 17 -1 (-5950 5750)(-5950 5650);
WIRE 17 -1 (-5950 5850)(-5950 5750);
FORCEPROP 2 LAST SIG_NAME M_B_CPU0_SA_DQS_DN<9:0>
J 2
(-5985 5860);
DISPLAY 0.489362 (-5985 5860);
WIRE 17 -1 (-3225 1500)(-3225 1550);
WIRE 17 -1 (-3225 1550)(-3225 1600);
WIRE 17 -1 (-3225 1600)(-3225 1650);
WIRE 17 -1 (-3225 1650)(-3225 1700);
WIRE 17 -1 (-3225 1750)(-3225 1700);
WIRE 17 -1 (-3225 1750)(-3225 1800);
WIRE 17 -1 (-3225 1850)(-3225 1800);
WIRE 17 -1 (-3225 1850)(-3225 1875);
WIRE 17 -1 (-3225 1875)(-2725 1875);
FORCEPROP 2 LAST SIG_NAME M_B_CPU0_SB_CB<7:0>
J 2
(-2725 1885);
DISPLAY 0.489362 (-2725 1885);
WIRE 17 -1 (-3225 1950)(-3225 2000);
WIRE 17 -1 (-3225 2000)(-3225 2050);
WIRE 17 -1 (-3225 2050)(-3225 2100);
WIRE 17 -1 (-3225 2100)(-3225 2150);
WIRE 17 -1 (-3225 2200)(-3225 2150);
WIRE 17 -1 (-3225 2200)(-3225 2250);
WIRE 17 -1 (-3225 2300)(-3225 2250);
WIRE 17 -1 (-3225 2300)(-3225 2325);
WIRE 17 -1 (-3225 2325)(-2725 2325);
FORCEPROP 2 LAST SIG_NAME M_B_CPU0_SA_CB<7:0>
J 2
(-2725 2335);
DISPLAY 0.489362 (-2725 2335);
WIRE 17 -1 (-3225 3050)(-3225 3000);
WIRE 17 -1 (-3225 3050)(-3225 3100);
WIRE 17 -1 (-3225 3000)(-3225 2950);
WIRE 17 -1 (-3225 2950)(-3225 2900);
WIRE 17 -1 (-3225 3100)(-3225 3150);
WIRE 17 -1 (-3225 3150)(-3225 3200);
WIRE 17 -1 (-3225 2900)(-3225 2850);
WIRE 17 -1 (-3225 2850)(-3225 2750);
WIRE 17 -1 (-3225 3200)(-3225 3300);
WIRE 17 -1 (-3225 3350)(-3225 3300);
WIRE 17 -1 (-3225 2750)(-3225 2700);
WIRE 17 -1 (-3225 2700)(-3225 2650);
WIRE 17 -1 (-3225 3400)(-3225 3350);
WIRE 17 -1 (-3225 3450)(-3225 3400);
WIRE 17 -1 (-3225 2650)(-3225 2600);
WIRE 17 -1 (-3225 2550)(-3225 2600);
WIRE 17 -1 (-3225 3500)(-3225 3450);
WIRE 17 -1 (-3225 3550)(-3225 3500);
WIRE 17 -1 (-3225 2500)(-3225 2550);
WIRE 17 -1 (-3225 2450)(-3225 2500);
WIRE 17 -1 (-3225 3600)(-3225 3550);
WIRE 17 -1 (-3225 3650)(-3225 3600);
WIRE 17 -1 (-3225 2400)(-3225 2450);
WIRE 17 -1 (-3225 3750)(-3225 3650);
WIRE 17 -1 (-3225 3800)(-3225 3750);
WIRE 17 -1 (-3225 3850)(-3225 3800);
WIRE 17 -1 (-3225 3900)(-3225 3850);
WIRE 17 -1 (-3225 3950)(-3225 3900);
WIRE 17 -1 (-3225 4000)(-3225 3950);
WIRE 17 -1 (-3225 4050)(-3225 4000);
WIRE 17 -1 (-3225 4100)(-3225 4050);
WIRE 17 -1 (-3225 4100)(-2600 4100);
FORCEPROP 2 LAST SIG_NAME M_B_CPU0_SB_DQ<31:0>
J 2
(-2660 4110);
DISPLAY 0.489362 (-2660 4110);
WIRE 17 -1 (-3225 4650)(-3225 4550);
WIRE 17 -1 (-3225 4700)(-3225 4650);
WIRE 17 -1 (-3225 4550)(-3225 4500);
WIRE 17 -1 (-3225 4500)(-3225 4450);
WIRE 17 -1 (-3225 4750)(-3225 4700);
WIRE 17 -1 (-3225 4800)(-3225 4750);
WIRE 17 -1 (-3225 4450)(-3225 4400);
WIRE 17 -1 (-3225 4350)(-3225 4400);
WIRE 17 -1 (-3225 4850)(-3225 4800);
WIRE 17 -1 (-3225 4850)(-3225 4900);
WIRE 17 -1 (-3225 4300)(-3225 4350);
WIRE 17 -1 (-3225 4250)(-3225 4300);
WIRE 17 -1 (-3225 4900)(-3225 4950);
WIRE 17 -1 (-3225 4950)(-3225 5000);
WIRE 17 -1 (-3225 4200)(-3225 4250);
WIRE 17 -1 (-3225 5000)(-3225 5100);
WIRE 17 -1 (-3225 5150)(-3225 5100);
WIRE 17 -1 (-3225 5200)(-3225 5150);
WIRE 17 -1 (-3225 5250)(-3225 5200);
WIRE 17 -1 (-3225 5300)(-3225 5250);
WIRE 17 -1 (-3225 5350)(-3225 5300);
WIRE 17 -1 (-3225 5400)(-3225 5350);
WIRE 17 -1 (-3225 5450)(-3225 5400);
WIRE 17 -1 (-3225 5550)(-3225 5450);
WIRE 17 -1 (-3225 5600)(-3225 5550);
WIRE 17 -1 (-3225 5650)(-3225 5600);
WIRE 17 -1 (-3225 5700)(-3225 5650);
WIRE 17 -1 (-3225 5750)(-3225 5700);
WIRE 17 -1 (-3225 5800)(-3225 5750);
WIRE 17 -1 (-3225 5850)(-3225 5800);
WIRE 17 -1 (-3225 5900)(-3225 5850);
WIRE 17 -1 (-3225 5900)(-2600 5900);
FORCEPROP 2 LAST SIG_NAME M_B_CPU0_SA_DQ<31:0>
J 2
(-2660 5910);
DISPLAY 0.489362 (-2660 5910);
WIRE 17 -1 (-5950 4800)(-6550 4800);
WIRE 17 -1 (-5950 5850)(-6550 5850);
WIRE 16 -1 (-3750 5275)(-3325 5275);
WIRE 16 -1 (-3750 5225)(-3325 5225);
WIRE 16 -1 (-3750 5175)(-3325 5175);
WIRE 16 -1 (-3750 5875)(-3325 5875);
WIRE 16 -1 (-3750 5125)(-3325 5125);
WIRE 16 -1 (-3750 5825)(-3325 5825);
WIRE 16 -1 (-3750 5775)(-3325 5775);
WIRE 16 -1 (-3750 5725)(-3325 5725);
WIRE 16 -1 (-3750 5675)(-3325 5675);
WIRE 16 -1 (-3750 5625)(-3325 5625);
WIRE 16 -1 (-3750 5575)(-3325 5575);
WIRE 16 -1 (-3750 5525)(-3325 5525);
WIRE 16 -1 (-3750 5425)(-3325 5425);
WIRE 16 -1 (-3750 5375)(-3325 5375);
WIRE 16 -1 (-3750 5325)(-3325 5325);
WIRE 16 -1 (-3750 4675)(-3325 4675);
WIRE 16 -1 (-3750 4625)(-3325 4625);
WIRE 16 -1 (-3750 4475)(-3325 4475);
WIRE 16 -1 (-3750 4425)(-3325 4425);
WIRE 16 -1 (-3750 5075)(-3325 5075);
WIRE 16 -1 (-3750 4375)(-3325 4375);
WIRE 16 -1 (-3750 4975)(-3325 4975);
WIRE 16 -1 (-3750 4325)(-3325 4325);
WIRE 16 -1 (-3750 4925)(-3325 4925);
WIRE 16 -1 (-3750 4275)(-3325 4275);
WIRE 16 -1 (-3750 4875)(-3325 4875);
WIRE 16 -1 (-3750 4825)(-3325 4825);
WIRE 16 -1 (-3750 4225)(-3325 4225);
WIRE 16 -1 (-3750 4175)(-3325 4175);
WIRE 16 -1 (-3750 4775)(-3325 4775);
WIRE 16 -1 (-3750 4725)(-3325 4725);
WIRE 16 -1 (-3750 4525)(-3325 4525);
WIRE 16 -1 (-3750 4075)(-3325 4075);
WIRE 16 -1 (-3750 4025)(-3325 4025);
WIRE 16 -1 (-3750 3525)(-3325 3525);
WIRE 16 -1 (-3750 3975)(-3325 3975);
WIRE 16 -1 (-3750 3475)(-3325 3475);
WIRE 16 -1 (-3750 3925)(-3325 3925);
WIRE 16 -1 (-3750 3425)(-3325 3425);
WIRE 16 -1 (-3750 3875)(-3325 3875);
WIRE 16 -1 (-3750 3375)(-3325 3375);
WIRE 16 -1 (-3750 3825)(-3325 3825);
WIRE 16 -1 (-3750 3325)(-3325 3325);
WIRE 16 -1 (-3750 3775)(-3325 3775);
WIRE 16 -1 (-3750 3275)(-3325 3275);
WIRE 16 -1 (-3750 3725)(-3325 3725);
WIRE 16 -1 (-3750 3175)(-3325 3175);
WIRE 16 -1 (-3750 3625)(-3325 3625);
WIRE 16 -1 (-3750 3125)(-3325 3125);
WIRE 16 -1 (-3750 3575)(-3325 3575);
WIRE 16 -1 (-3750 3075)(-3325 3075);
WIRE 16 -1 (-3750 2175)(-3325 2175);
WIRE 16 -1 (-3750 2125)(-3325 2125);
WIRE 16 -1 (-3750 2075)(-3325 2075);
WIRE 16 -1 (-3750 2425)(-3325 2425);
WIRE 16 -1 (-3750 2375)(-3325 2375);
WIRE 16 -1 (-3750 2925)(-3325 2925);
WIRE 16 -1 (-3750 2875)(-3325 2875);
WIRE 16 -1 (-3750 2825)(-3325 2825);
WIRE 16 -1 (-3750 2725)(-3325 2725);
WIRE 16 -1 (-3750 2675)(-3325 2675);
WIRE 16 -1 (-3750 2625)(-3325 2625);
WIRE 16 -1 (-3750 2575)(-3325 2575);
WIRE 16 -1 (-3750 2525)(-3325 2525);
WIRE 16 -1 (-3750 2475)(-3325 2475);
WIRE 16 -1 (-3750 2275)(-3325 2275);
WIRE 16 -1 (-3750 2225)(-3325 2225);
WIRE 16 -1 (-3750 3025)(-3325 3025);
WIRE 16 -1 (-3750 2975)(-3325 2975);
WIRE 16 -1 (-3750 2025)(-3325 2025);
WIRE 16 -1 (-3750 1825)(-3325 1825);
WIRE 16 -1 (-3750 1975)(-3325 1975);
WIRE 16 -1 (-3750 1775)(-3325 1775);
WIRE 16 -1 (-3750 1925)(-3325 1925);
WIRE 16 -1 (-3750 1725)(-3325 1725);
WIRE 16 -1 (-3750 1675)(-3325 1675);
WIRE 16 -1 (-3750 1625)(-3325 1625);
WIRE 16 -1 (-3750 1575)(-3325 1575);
WIRE 16 -1 (-3750 1525)(-3325 1525);
WIRE 16 -1 (-3750 1475)(-3325 1475);
WIRE 16 -1 (-5850 5825)(-5350 5825);
WIRE 16 -1 (-5850 5725)(-5350 5725);
WIRE 16 -1 (-5850 5625)(-5350 5625);
WIRE 16 -1 (-5850 5525)(-5350 5525);
WIRE 16 -1 (-5850 5425)(-5350 5425);
WIRE 16 -1 (-5650 5875)(-5350 5875);
WIRE 16 -1 (-5850 5325)(-5350 5325);
WIRE 16 -1 (-5650 5775)(-5350 5775);
WIRE 16 -1 (-5850 5225)(-5350 5225);
WIRE 16 -1 (-5650 5675)(-5350 5675);
WIRE 16 -1 (-5850 5125)(-5350 5125);
WIRE 16 -1 (-5650 5575)(-5350 5575);
WIRE 16 -1 (-5650 5475)(-5350 5475);
WIRE 16 -1 (-5650 5375)(-5350 5375);
WIRE 16 -1 (-5650 5275)(-5350 5275);
WIRE 16 -1 (-5650 5175)(-5350 5175);
WIRE 16 -1 (-5650 4325)(-5350 4325);
WIRE 16 -1 (-5650 4225)(-5350 4225);
WIRE 16 -1 (-5650 4125)(-5350 4125);
WIRE 16 -1 (-5850 4775)(-5350 4775);
WIRE 16 -1 (-5850 4675)(-5350 4675);
WIRE 16 -1 (-5850 4575)(-5350 4575);
WIRE 16 -1 (-5850 5025)(-5350 5025);
WIRE 16 -1 (-5850 4475)(-5350 4475);
WIRE 16 -1 (-5850 4925)(-5350 4925);
WIRE 16 -1 (-5850 4375)(-5350 4375);
WIRE 16 -1 (-5650 4825)(-5350 4825);
WIRE 16 -1 (-5850 4275)(-5350 4275);
WIRE 16 -1 (-5650 4725)(-5350 4725);
WIRE 16 -1 (-5850 4175)(-5350 4175);
WIRE 16 -1 (-5650 4625)(-5350 4625);
WIRE 16 -1 (-5650 5075)(-5350 5075);
WIRE 16 -1 (-5650 4525)(-5350 4525);
WIRE 16 -1 (-5650 4975)(-5350 4975);
WIRE 16 -1 (-5650 4425)(-5350 4425);
WIRE 16 -1 (-5850 3875)(-5350 3875);
WIRE 16 -1 (-5650 4025)(-5350 4025);
WIRE 16 -1 (-5850 3725)(-5350 3725);
WIRE 16 -1 (-5850 3325)(-5350 3325);
WIRE 16 -1 (-5850 3675)(-5350 3675);
WIRE 16 -1 (-5850 3275)(-5350 3275);
WIRE 16 -1 (-5850 3625)(-5350 3625);
WIRE 16 -1 (-5850 3225)(-5350 3225);
WIRE 16 -1 (-5850 3575)(-5350 3575);
WIRE 16 -1 (-5850 3175)(-5350 3175);
WIRE 16 -1 (-5850 3525)(-5350 3525);
WIRE 16 -1 (-5850 3125)(-5350 3125);
WIRE 16 -1 (-5850 3475)(-5350 3475);
WIRE 16 -1 (-5850 3075)(-5350 3075);
WIRE 16 -1 (-5850 3425)(-5350 3425);
WIRE 16 -1 (-5850 4075)(-5350 4075);
WIRE 16 -1 (-5850 3975)(-5350 3975);
WIRE 16 -1 (-5650 3925)(-5350 3925);
WIRE 16 -1 (-5850 3025)(-5350 3025);
WIRE 16 -1 (-6450 1925)(-5350 1925);
FORCEPROP 2 LAST SIG_NAME M_B_CPU0_RESET_N
J 0
(-6450 1935);
DISPLAY 0.489362 (-6450 1935);
WIRE 16 -1 (-6450 2225)(-5350 2225);
FORCEPROP 2 LAST SIG_NAME M_B_CPU0_SB_RSP<0>
J 0
(-6450 2235);
DISPLAY 0.489362 (-6450 2235);
WIRE 16 -1 (-6450 2125)(-5350 2125);
FORCEPROP 2 LAST SIG_NAME M_B_CPU0_SB_PAR
J 0
(-6450 2135);
DISPLAY 0.489362 (-6450 2135);
WIRE 16 -1 (-6450 2325)(-5350 2325);
FORCEPROP 2 LAST SIG_NAME M_B_CPU0_SB_CS_N<1>
J 0
(-6450 2335);
DISPLAY 0.489362 (-6450 2335);
WIRE 16 -1 (-6450 2375)(-5350 2375);
FORCEPROP 2 LAST SIG_NAME M_B_CPU0_SB_CS_N<0>
J 0
(-6450 2385);
DISPLAY 0.489362 (-6450 2385);
WIRE 16 -1 (-6450 2475)(-5350 2475);
FORCEPROP 2 LAST SIG_NAME M_B_CPU0_SA_PAR
J 0
(-6450 2485);
DISPLAY 0.489362 (-6450 2485);
WIRE 16 -1 (-6450 2675)(-5350 2675);
FORCEPROP 2 LAST SIG_NAME M_B_CPU0_SA_CS_N<1>
J 0
(-6450 2685);
DISPLAY 0.489362 (-6450 2685);
WIRE 16 -1 (-6450 2725)(-5350 2725);
FORCEPROP 2 LAST SIG_NAME M_B_CPU0_SA_CS_N<0>
J 0
(-6450 2735);
DISPLAY 0.489362 (-6450 2735);
WIRE 16 -1 (-6450 2825)(-5350 2825);
FORCEPROP 2 LAST SIG_NAME M_B_CPU0_CLK_DN<0>
J 0
(-6450 2835);
DISPLAY 0.489362 (-6450 2835);
WIRE 16 -1 (-6450 2875)(-5350 2875);
FORCEPROP 2 LAST SIG_NAME M_B_CPU0_CLK_DP<0>
J 0
(-6450 2885);
DISPLAY 0.489362 (-6450 2885);
WIRE 16 -1 (-6450 1075)(-5350 1075);
FORCEPROP 2 LAST SIG_NAME TP_M_B_CPU0_SA_TEST39B
J 0
(-6435 1085);
DISPLAY 0.489362 (-6435 1085);
FORCEPROP 2 LASTPROP $XRERR UNIQUE?
J 0
(-6690 1075);
DISPLAY 0.638298 (-6690 1075);
PAINT MONO (-6690 1075);
DISPLAY INVISIBLE (-6690 1075);
WIRE 16 -1 (-7650 2025)(-6925 2025);
FORCEPROP 2 LAST SIG_NAME M_B_CPU0_ALERT_N
J 0
(-7610 2035);
DISPLAY 0.489362 (-7610 2035);
WIRE 16 -1 (-6725 2025)(-5350 2025);
FORCEPROP 2 LAST SIG_NAME M_B_CPU0_ALERT_R_N
J 0
(-6435 2035);
DISPLAY 0.489362 (-6435 2035);
FORCEPROP 2 LASTPROP $XRERR UNIQUE?
J 0
(-6675 2035);
DISPLAY 0.638298 (-6675 2035);
PAINT MONO (-6675 2035);
DISPLAY INVISIBLE (-6675 2035);
WIRE 16 -1 (-6450 2575)(-5350 2575);
FORCEPROP 2 LAST SIG_NAME M_B_CPU0_SA_RSP<0>
J 0
(-6450 2585);
DISPLAY 0.489362 (-6450 2585);
QUIT
